# Grand teton__Component BOM_20221226.xlsx — Main-VR RTT + MPS5990 (bom)
| S.No. | PART_NUMBER | Part Description | Manufacturer | Manufacturing Part Number | Quantity | Location (CRD) |
| 1 | AJ004400000 | IC OTHER(100P)9SQ440NQQI8(QFN) | INTEGRATED DEVICE TECHNOLOGY,INC. | 9SQ440NQQI8 | 1 | U13 |
| 2 | AJ020010003 | IC OTHER(80P)9QXL2001BNHGI8(GQFN) | INTEGRATED DEVICE TECHNOLOGY,INC. | 9QXL2001BNHGI8 | 1 | U38 |
| 3 | AR0F0TP4024 | IC(484P)LCMXO3LF-9400C-5BG484C(CABGA) | LATTICE SEMICONDUCTOR CORP., | LCMXO3LF-9400C-5BG484C | 1 | U249 |
| 4 | AJ0Q0ET0T03 | IC (749P)EMMITSBURG Q0ET(FCBGA) FABCON | INTEL SEMICONDUCTOR LTD. | GGNOCPU04762800-Q0ET-MM#99AVKL | 1 | U4 |
| 5 | AKE30Z00613 | IC(8P) EEPROM M24128-BWMN6TP(SO8) | STMICROELCTRONICS | M24128-BWMN6TP | 1 | U64 |
| 9 | AL000230001 | IC OTHER (16P) INA230AIRGTR (QFN 3X3) | TEXAS INSTRUMENTS SUPPLY CO., | INA230AIRGTR | 5 | U263,U264,U265,U266,U276 |
| 10 | AL000251001 | IC OTHER(24P)9FGL0251CKILFT(VFQFPN) | Renesas Technology Taiwan Co., Ltd. | 9FGL0251CKILFT | 1 | U247 |
| 11 | AL000257W24 | IC OTHER(16P)QS3VH257QG8(QSOP) | INTEGRATED DEVICE TECHNOLOGY,INC. | QS3VH257QG8 | 2 | U14,U15 |
| 12 | AL000304K01 | IC OTHER(8P) PI6CV304LE(TSSOP) | PERICOM SEMICONDUCTOR CORPORATION | PI6CV304LEX | 1 | U90 |
| 13 | AL000451003 | IC OTHER(32P) 9ZXL0451EKILFT(VFQFPN) | INTEGRATED DEVICE TECHNOLOGY,INC. | 9ZXL0451EKILFT | 1 | U314 |
| 14 | AL000682001 | IC CTRL(13P)NB682GD-Z(QFN) | Monolithic Power Systems, Inc (MPS International Ltd.) | NB682GD-Z | 1 | PU74 |
| 15 | AL000852001 | IC CTRL(28P) GL852G-OHY60(QFN) | Genesys Logic, Inc. (Genesys Logic America, Inc.) | GL852G-OHY60 | 1 | U268 |
| 16 | AL001002007 | IC OTHERS(24P) PI3EQX1002EZREX(TQFN) | DIODES TAIWAN CO.,LTD. | PI3EQX1002EZREX | 1 | U309 |
| 17 | AL001086001 | IC OTHER(6P)ADM1086AKSZ-REEL7(SC70) | ANALOG DEVICES | ADM1086AKSZ-REEL7 | 1 | U94 |
| 18 | AL001G66000 | IC(5P) 74LVC1G66GV(SOT753) | PHILIPS  LTD,. | 74LVC1G66GV | 3 | U16,U320,U321 |
| 19 | AL002014K01 | IC OTHER(14P) GTL2014PW(TSSOP) | NXP semiconductors | GTL2014PW | 6 | U83,U84,U301,U304,U305,U306 |
| 20 | AL002267000 | IC(10P)NX3L2267GM(XQFN) | NXP semiconductors | NX3L2267GM | 2 | U96,U97 |
| 21 | AL002G07003 | IC OTHER(6P)74LVC2G07DW-7(SOT-363) | DIODES TAIWAN CO.,LTD. | 74LVC2G07DW-7 | 8 | U58,U59,U134,U211,U212,U255,U257,U308 |
| 22 | AL002G07006 | IC(6P) SN74LVC2G07DCKR(SC70-6) | TEXAS INSTRUMENTS SUPPLY CO., | SN74LVC2G07DCKR | 1 | U259 |
| 23 | AL003126K08 | IC OTHER(14P) 74CBTLV3126PW(TSSOP) | NXP semiconductors | 74CBTLV3126PW | 8 | U17,U18,U67,U68,U86,U222,U223,U327 |
| 24 | AL003889000 | IC OTHER(37P) IR3889MTRPBF(QFN) | INFINEON TECHNOLOGIES ASIA PACIFIC | IR3889MTRPBF | 1 | PU9 |
| 26 | AL004307000 | IC OTHER(8P) LTC4307CMS8#TRPBF(MSOP) | LINEAR TECHNOLOGY CORPORATION | LTC4307CMS8#TRPBF | 4 | U175,U192,U194,U200 |
| 29 | AR0F0TP4023 | PROG IC(45P)MP5990GMA-1111-Z(F9C2)(LGA) | Monolithic Power Systems, Inc (MPS International Ltd.) | MP5990GMA-1111-Z | 1 | PU289 |
| 30 | AL005991A00 | IC(32P)MP5991GLU-Z(LGA) | Monolithic Power Systems, Inc (MPS International Ltd.) | MP5991GLU-Z | 4 | PU287,PU288,PU296,PU297 |
| 31 | AL006700001 | IC OTHER(6P)LT6700CS6-1#TRPBF(TSOT-23) | LINEAR TECHNOLOGY CORPORATION | LT6700CS6-1#TRPBF | 1 | U206 |
| 32 | AL0075BD000 | IC OTHER (8P) LM75BD(SO8) | NXP semiconductors | LM75BD | 4 | U270,U271,U272,U273 |
| 34 | AL009306K04 | IC OTHER(8P)PCA9306DP1(TSSOP) | NXP semiconductors | PCA9306DP1 | 1 | U98 |
| 35 | AL009517000 | IC OTHER (8P) I2C PCA9517AD (SO8) | NXP semiconductors | PCA9517AD | 2 | U30,U31 |
| 36 | AL009539K07 | IC OTHER(24P)PCA9539RPW(TSSOP) | NXP semiconductors | PCA9539RPW | 1 | U181 |
| 37 | AL009545K17 | IC (20P) PCA9545APW (TSSOP) | PHILIPS  LTD,. | PCA9545APW | 1 | U143 |
| 38 | AL009548K02 | IC OTHER(24P) TCA9548APWR(TSSOP) | TEXAS INSTRUMENTS SUPPLY CO., | TCA9548APWR | 2 | U36,U39 |
| 39 | AL009555K07 | IC OTHER(24P)PCA9555APW(TSSOP) | PHILIPS  LTD,. | PCA9555PW | 2 | U51,U209 |
| 40 | AL009617K02 | IC OTHER(8P) PCA9617ADP(TSSOP) | NXP semiconductors | PCA9617ADP | 6 | U28,U29,U235,U236,U279,U315 |
| 41 | AL009818001 | IC OTHER(3P)RT9818C-44GV(SOT23-3) | RICHTEK TECHNOLOGY CORPORATION | RT9818C-44GV | 1 | U99 |
| 42 | AL011617W00 | IC CTRL(16P)MAX11617EEE+T QSOP | MAXIM JAPAN CO.,LTD(DALLAS SEMICONDUCTOR CORP.) | MAX11617EEE+T | 1 | U193 |
| 43 | AL012902001 | IC OTHER(30P)PI3EQX12902AZLEX(TQFN) | PERICOM SEMICONDUCTOR CORPORATION | PI3EQX12902AZLEX | 1 | U237 |
| 44 | AL015080B00 | IC OTHER(28P)MAX15090BEWI+T(WLP) | MAXIM JAPAN CO.,LTD(DALLAS SEMICONDUCTOR CORP.) | MAX15090BEWI+T | 2 | PU200,PU202 |
| 47 | AL015080B00 | IC OTHER(28P)MAX15090BEWI+T(WLP) | MAXIM JAPAN CO.,LTD(DALLAS SEMICONDUCTOR CORP.) | MAX15090BEWI+T | 1 | PU295 |
| 48 | AL015080B00 | IC OTHER(28P)MAX15090BEWI+T(WLP) | MAXIM JAPAN CO.,LTD(DALLAS SEMICONDUCTOR CORP.) | MAX15090BEWI+T | 1 | PU300 |
| 53 | AL053317005 | IC(14P)RS53317LR(QFN) | Reed Semiconductor Corporation | RS53317LR | 2 | PU81,PU82 |
| 54 | AL053318002 | IC(21P)RS53318LR(QFN) | Reed Semiconductor Corporation | RS53318LR | 3 | PU79,PU80,PU181 |
| 55 | AL053319002 | IC(21P)RS53319LR(QFN) | Reed Semiconductor Corporation | RS53319LR | 1 | PU73 |
| 56 | AR0F0TP4015 | PROG IC(41P)ISL69260IRAZ-T(QFN) | Renesas Technology Taiwan Co., Ltd. | ISL69260IRAZ-T | 4 | PU5,PU18,PU22,PU35 |
| 57 | AL080929000 | IC OTHER(3P) APX809-29SAG-7(SOT23) | DIODES TAIWAN CO.,LTD. | APX809-29SAG-7 | 4 | U52,U216,U330,U336 |
| 58 | AL099390004 | IC CTRL(41P) ISL99390FRZ-TR5935(QFN) | Renesas Technology Taiwan Co., Ltd. | ISL99390FRZ-TR5935 | 30 | PU6_P0_8,PU7_P0_7,PU8_P0_6,PU9_P0_5,PU10_P0_4,PU11_P0_3,PU12_P0_2,PU13_P0_1,PU17,PU23_P1_8,PU24_P1_7,PU25_P1_6,PU26_P1_5,PU27_P1_4,PU28_P1_3,PU30_P1_2,PU31_P1_1,PU36,PU43_P0_1,PU44_P0_2,PU50_P1_1,PU51_P1_2,PU69_P0_1,PU70_P0_2,PU71_P0_3,PU72_P0_4,PU75_P1_1,PU76_P1_2,PU77_P1_3,PU78_P1_4 |
| 59 | AL1G0007001 | IC OTHER(5P) 74LVC1G07GV(SOT753) | NXP semiconductors | 74LVC1G07GV | 4 | U104,U157,U218,U219 |
| 60 | AL1G0008020 | IC OTHER(5P) 74LVC1G08W5-7(SOT25) | DIODES TAIWAN CO.,LTD. | 74LVC1G08W5-7 | 9 | U50,U53,U208,U210,U278,U322,U323,U334,U335 |
| 61 | AL1G0017K01 | IC OTHER(5P) 74LVC1G17GW(TSSOP) | NXP semiconductors | 74LVC1G17GW | 2 | U75,U207 |
| 62 | AL1G0126009 | IC OTHER(5P) 74LVC1G126SE-7 (SOT353) | DIODES TAIWAN CO.,LTD. | 74LVC1G126SE-7 | 9 | U66,U82,U145,U204,U217,U224,U225,U239,U286 |
| 63 | AL1G07SE000 | IC OTHER(5P)74LVC1G07SE-7(SOT353) | DIODES TAIWAN CO.,LTD. | 74LVC1G07SE-7 | 2 | U95,U154 |
| 64 | AL221340002 | IC (29P) RAA2213404GNP#HB0(PQFN) | Renesas Technology Taiwan Co., Ltd. | RAA2213404GNP#HB0 | 2 | PU42,PU49 |
| 65 | AR0F0TP4016 | PROG IC(49P)RAA229126GNP#HA0(QFN) | Renesas Technology Taiwan Co., Ltd. | RAA229126GNP#HA0 | 2 | PU14,PU29 |
| 66 | AL2G0017005 | IC(6P) 74LVC2G17GW (SC-88) | PHILIPS  LTD,. | 74LVC2G17GW | 7 | U150,U195,U196,U252,U253,U256,U316 |
| 67 | ALSB3157000 | IC(6P) NC7SB3157P6X(SC70-6) | FAIRCHILD SEMICONDUCTOR | NC7SB3157P6X | 6 | U21,U22,U60,U61,U85,U142 |
| 68 | ALVC1G02000 | IC(5P) 74LVC1G02GW(SOT353) | PHILIPS  LTD,. | 74LVC1G02GW | 1 | U23 |
| 69 | ALVC1G32007 | IC(5P)74LVC1G32GW (SC70-5) | PHILIPS  LTD,. | 74LVC1G32GW | 1 | U248 |
| 70 | ALVC2G08K01 | IC OTHER(8P) 74LVC2G08DP(TSSOP) | NXP semiconductors | 74LVC2G08DP | 3 | U240,U241,U242 |
| 71 | BA008470026 | TRANS SMD BC847BPN(45V,0.1A,0.3W) | Nexperia B.V. | BC847BPN | 6 | Q138,Q139,Q140,Q141,Q142,Q143 |
| 73 | BAM138K0000 | TRANS MOS BSS138K(50V,0.22A,0.35W) | FAIRCHILD SEMICONDUCTOR | BSS138K | 7 | U49,U70,U87,U89,U215,U307,U325 |
| 74 | BAM138K0003 | TRANS MOSFET PJT138K(50V,0.36A,0.236W) | PAN JIT INTERNATIONAL INC. | PJT138K | 52 | Q15,Q16,Q37,Q50,Q67,Q69,Q70,Q71,Q72,Q74,Q75,Q76,Q77,Q78,Q79,Q80,Q81,Q83,Q84,Q85,Q86,Q87,Q88,Q95,Q96,Q101,Q102,Q103,Q104,Q106,Q107,Q108,Q128,Q129,Q130,Q131,Q132,Q133,Q134,Q135,Q136,Q137,Q144,Q145,Q146,Q148,Q150,Q151,Q152,Q153,Q154,Q236 |
| 76 | BAM138K0003 | TRANS MOSFET PJT138K(50V,0.36A,0.236W) | PAN JIT INTERNATIONAL INC. | PJT138K | 2 | Q119,Q124 |
| 77 | BAM138K0003 | TRANS MOSFET PJT138K(50V,0.36A,0.236W) | PAN JIT INTERNATIONAL INC. | PJT138K | 1 | Q125 |
| 78 | BAM138K0003 | TRANS MOSFET PJT138K(50V,0.36A,0.236W) | PAN JIT INTERNATIONAL INC. | PJT138K | 1 | Q126 |
| 80 | BAM60080000 | TRANS MOS NX6008NBKS(60V, 0.22A,260W) | Nexperia B.V. | NX6008NBKS | 5 | Q97,Q98,Q99,Q100,Q105 |
| 81 | BAM70020002 | TR MOSFET 2N7002K(60V,300MA,0.35W)SOT-23 | PAN JIT INTERNATIONAL INC. | 2N7002K | 11 | Q33,Q34,Q35,Q39,Q46,Q52,Q53,Q54,U158,U290,U324 |
| 83 | BAMNR580000 | TRANS MOS PSMNR58-30YLH(30V,380A,333W) | Nexperia B.V. | PSMNR58-30YLH | 2 | Q56,Q57 |
| 84 | BC000340033 | DIODE SMD SDMK0340L-7-F(40V,30MA) | DIODES TAIWAN CO.,LTD. | SDMK0340L-7-F | 1 | D145 |
| 85 | BC000340Z30 | DIODE SMD B340A-13-F(40V,3A)SCHOTTKY | DIODES TAIWAN CO.,LTD. | B340A-13-F | 7 | PD102,PD103,PD108,PD109,PD112,PD113,PD116 |
| 86 | BC000530Z41 | DIODE SMD B0530WS-7-F(30V,0.5A)SOD-323 | DIODES TAIWAN CO.,LTD. | B0530WS-7-F | 8 | D42,D43,D44,D45,D46,D47,D48,D49 |
| 87 | BC005819Z40 | DIODE SMD 1N5819HW-7-F(40V.1A.SOD123) | DIODES TAIWAN CO.,LTD. | 1N5819HW-7-F | 1 | D141 |
| 88 | BC015P3SZ00 | DIODE SMD SS15P3S-M3/86A(30V,15A) | SILICONIX TAIWAN LTD.(VISHAY SILICONIX ; VISHAY TEMIC ; VISHAY TELFUNKEN)Vishay Intertechnology Corp......(Skip) | SS15P3S-M3/86A | 1 | PD17 |
| 89 | BC0BAS70Z01 | DIODE SMD BAS70-05-7-F(70V,SHTKY,SOT-23) | DIODES TAIWAN CO.,LTD. | BAS70-05-7-F | 1 | U62 |
| 90 | BC0BAT54Z53 | DIODE BAT54-7-F(30V.200MA SCHOTTKY) | DIODES TAIWAN CO.,LTD. | BAT54-7-F | 1 | D7 |
| 91 | BC0MDJ14000 | DIODE SMD 5.0SMDJ14A(14V,216A,5000W) | LITTELFUSE INC. | 5.0SMDJ14A | 2 | PD15,PD16 |
| 92 | BCSMF14AZ01 | DIODE SMF14A(14V,8.6A)SOD-123FL | LITTELFUSE INC. | SMF14A | 4 | PD101,PD107,PD114,PD115 |
| 93 | BEBL0172Z00 | LED SMD(2P) BLUE(LTST-C281TBKT-5A) | LITEON ELECTRONIC CO., LTD. | LTST-C281TBKT-5A | 38 | D0,D65,D66,D67,D68,D69,D70,D71,D72,D73,D74,D75,D76,D77,D78,D79,D80,D81,D82,D83,D84,D85,D86,D87,D88,D89,D90,D91,D92,D93,D94,D95,D96,D97,D98,D99,D142,D143 |
| 94 | BEYL0159Z00 | LED SMD(2P)YELLOW(LTST-C190KSKT-P) | LITE-ON  CORP.(LITE-ON IT CORPORATION)Lite-On Semiconductor Corp. | LTST-C190KSKT-P | 2 | D6,D144 |
| 95 | BF625000014 | OSC SMD 25MHZ(+-25PPM,3.3V)FJ2500009 | ECERA COMTEK CORPORATION (Pericom SaRonix Ecera Technology Corporation) P.S.E | FJ2500009 | 1 | OSC2 |
| 96 | BF650000032 | OSC SMD 50MHZ(25PPM,15PF,3.3V)FK5000023 | ECERA COMTEK CORPORATION (Pericom SaRonix Ecera Technology Corporation) P.S.E | FK5000023 | 1 | OSC1 |
| 97 | BG6120000E0 | XTAL 12MHZ(+-20PPM,10PF)E2SB12E00000EE | HANGZHOU HOSONIC ELECTRONIC CO.,LTD (Hosonic Electronic Co., Ltd.) | E2SB12E00000EE | 1 | Y4 |
| 98 | BG6250000F0 | XTAL SMD 25MHZ(+-10PPM,8PF)FL2500498 | DIODES TAIWAN CO.,LTD. | FL2500498 | 2 | Y2,Y3 |
| 99 | BG632768012 | CRYSTAL SMD 32.768KHZ(+-20PPM,12.5PF) | TAIWAN X'TAL CORPATION (TXC Corporation) | 9H03220009 | 1 | Y1 |
| 100 | CC71003MZ30 | CAP OSCON SMD 100U 16V(20%,5*5.8)NPN | NIPPON CHEMI-CON | APXG160ARA101ME61G | 1 | PC1215 |
| 101 | CC72201MZ28 | CAP OSCON SMD 220U 6.3V(20%,5*5.8)NPN | NIPPON CHEMI-CON | APXF6R3ARA221ME611 | 1 | PC1845 |
| 102 | CC72703MD38 | CAPOSCON DIP 270U16V(20%,ESR10,6.3*8)NPN | NIPPON CHEMI-CON | APSG160ETD271MF08J | 20 | PC3,PC207,PC208,PC315,PC318,PC321,PC324,PC417,PC460,PC461,PC566,PC579,PC582,PC585,PC588,PC622,PC1189,PC1210,PC2345,PC2346 |
| 103 | CC75601MD16 | CAP OSCON DIP 560U 6.3V(+-20%,6.3*8)NPN | NIPPON CHEMI-CON | APSE6R3ETD561MF08S | 4 | PC1258,PC1771,PC1866,PC1867 |
| 104 | CC7560JMD16 | CAP OSCON DIP 560U 2.5V(20%,5*8)SAY | NIPPON CHEMI-CON | APSK2R5ETX561ME08S | 36 | PC16,PC83,PC316,PC319,PC322,PC325,PC384,PC385,PC414,PC415,PC416,PC580,PC583,PC586,PC589,PC619,PC620,PC621,PC1183,PC1185,PC1186,PC1201,PC1203,PC1204,PC1227,PC1230,PC1574,PC1576,PC1579,PC1593,PC1595,PC1596,PC1644,PC1645,PC2180,PC2199 |
| 105 | CH-8216TB09 | CAP CHIP 8.2P 50V (+-0.1P NP0 0402) | MURATA ERIE N.A. INC TAIWAN BRANCH Okayama Murata Mfg.Co.,Ltd.Wakura Murata Mfg. Co., Ltd. (Peregrine Semiconductor Corp) | GRM1555C1H8R2B | 4 | C2036,C2037,C2255,C2256 |
| 106 | CH01806JB07 | CAP CHIP 18P 50V(+-5% C0G 0402) | ACER PERIPHERALS INC.(Darfon Electronics Corp.) Darfon Precisions(Suzhou)Co.,LTD | C1005NP0180JGT | 2 | C1507,C1508 |
| 107 | CH01806JB07 | CAP CHIP 18P 50V(+-5% C0G 0402) | ACER PERIPHERALS INC.(Darfon Electronics Corp.) Darfon Precisions(Suzhou)Co.,LTD | C1005NP0180JGT | 2 | C2029,C2030 |
| 110 | CH04706JB01 | CHIP0402 | ACER PERIPHERALS INC.(Darfon Electronics Corp.) Darfon Precisions(Suzhou)Co.,LTD | C1005NP0470JGT | 1 | PC1877 |
| 111 | CH11006JB00 | CAP CHIP 100P 50V(+-5%,NPO,0402) | ACER PERIPHERALS INC.(Darfon Electronics Corp.) Darfon Precisions(Suzhou)Co.,LTD | CC0402N101J3SST-S | 2 | C1209,C1211 |
| 112 | CH11006JB18 | CAP CHIP 100P 50V(+-5%.X7R.0402) | ACER PERIPHERALS INC.(Darfon Electronics Corp.) Darfon Precisions(Suzhou)Co.,LTD | C1005X7R101JGT | 8 | C1344,C2042,C2043,C2044,C2045,C2175,C2176,C2195 |
| 116 | CH12206KB14 | CAP CHIP 220P 50V(+-10%,X7R,0402) | ACER PERIPHERALS INC.(Darfon Electronics Corp.) Darfon Precisions(Suzhou)Co.,LTD | C1005X7R221KGT | 1 | PC2182 |
| 117 | CH12206KB14 | CAP CHIP 220P 50V(+-10%,X7R,0402) | ACER PERIPHERALS INC.(Darfon Electronics Corp.) Darfon Precisions(Suzhou)Co.,LTD | C1005X7R221KGT | 1 | PC569 |
| 118 | CH14706KB18 | CHIP0402 | ACER PERIPHERALS INC.(Darfon Electronics Corp.) Darfon Precisions(Suzhou)Co.,LTD | C1005X7R471KGT | 10 | PC100,PC101,PC222,PC336,PC393,PC475,PC554,PC631,PC1271,PC1292 |
| 121 | CH16806KB17 | CAP CHIP 680P 50V(+-10%,X7R,0402) | ACER PERIPHERALS INC.(Darfon Electronics Corp.) Darfon Precisions(Suzhou)Co.,LTD | C1005X7R681KGT | 4 | PC237,PC238,PC1223,PC1266 |
| 122 | CH1686K1B09 | CAP CHIP 680P 50V(+-10%,X7R,0402)MUR | MURATA ERIE N.A. INC TAIWAN BRANCH Okayama Murata Mfg.Co.,Ltd.Wakura Murata Mfg. Co., Ltd. (Peregrin......(Skip) | GRM155R71H681K | 1 | PC1253 |
| 123 | CH21006JB10 | CAP CHIP 1000P 50V(+-5%,X7R,0402) | ACER PERIPHERALS INC.(Darfon Electronics Corp.) Darfon Precisions(Suzhou)Co.,LTD | C1005X7R102JGT | 12 | C1296,C1297,C1301,C2446,C2451,C2452,C2460,C2860,C3267,C3268,C3274,C3275 |
| 125 | CH2336K1B12 | CHIP0402 | ACER PERIPHERALS INC.(Darfon Electronics Corp.) Darfon Precisions(Suzhou)Co.,LTD | C1005X7R332KGT | 44 | PC27,PC28,PC176,PC189_P0_1,PC190_P0_2,PC215,PC216,PC230_P0_8,PC231_P0_7,PC252_P0_6,PC253_P0_5,PC274_P0_4,PC275_P0_3,PC296_P0_2,PC297_P0_1,PC331,PC374,PC389,PC397_P1_1,PC398_P1_2,PC422,PC429,PC442_P1_1,PC443_P1_2,PC468,PC469,PC483_P1_8,PC484_P1_7,PC505_P1_6,PC506_P1_5,PC527_P1_4,PC528_P1_3,PC549,PC560_P1_2,PC561_P1_1,PC594,PC602_P0_1,PC603_P0_2,PC627,PC634,PC1173_P0_3,PC1174_P0_4,PC1193_P1_3,PC1194_P1_4 |
| 128 | CH23906KB14 | CAP CHIP 3900P 50V(+-10%,X7R,0402) | ACER PERIPHERALS INC.(Darfon Electronics Corp.) Darfon Precisions(Suzhou)Co.,LTD | C1005X7R392KGT | 1 | PC2237 |
| 129 | CH2686K1B01 | CAP CHIP 6800P 50V(+-10%,X7R,0402) | ACER PERIPHERALS INC.(Darfon Electronics Corp.) Darfon Precisions(Suzhou)Co.,LTD | C1005X7R682KGT | 2 | PC2089,PC2151 |
| 130 | CH2686K1B01 | CAP CHIP 6800P 50V(+-10%,X7R,0402) | ACER PERIPHERALS INC.(Darfon Electronics Corp.) Darfon Precisions(Suzhou)Co.,LTD | C1005X7R682KGT | 1 | PC2216 |
| 131 | CH30106KB19 | CAP CHIP 0.001U 50V(10%,X7R,0402) | AVX CORPARATION CO., LTD. | 04025C102KAT2A | 1 | PC2192 |
| 132 | CH31004KB17 | CAP CHIP 0.01U 25V(+-10%,X7R,0402) | MURATA ERIE N.A. INC TAIWAN BRANCH Okayama Murata Mfg.Co.,Ltd.Wakura Murata Mfg. Co., Ltd. (Peregrine Semiconductor Corp) | WBM155R71E103K | 5 | PC1420,PC1421,PC2277,PC2279,PC2282 |
| 133 | CH31006KB18 | CAP CHIP 0.01U 50V(+-10%,X7R,0402) | ACER PERIPHERALS INC.(Darfon Electronics Corp.) Darfon Precisions(Suzhou)Co.,LTD | C1005X7R103KGT | 44 | C1113,C1118,C1124,C1127,C1133,C1138,C1142,C1146,C1152,C1154,C1893,C1894,C1895,C1896,C1897,C1898,C1899,C1900,C1901,C1902,C1903,C1904,C1908,C1909,C1910,C1911,C1912,C1913,C1914,C1915,C1916,C1917,C1918,C1919,C1926,C1927,C1928,C1929,C1930,C1931,C1932,C1933,C1934,C2287 |
| 134 | CH31006KB18 | CAP CHIP 0.01U 50V(+-10%,X7R,0402) | ACER PERIPHERALS INC.(Darfon Electronics Corp.) Darfon Precisions(Suzhou)Co.,LTD | C1005X7R103KGT | 2 | PC2189,PC2190 |
| 135 | CH32203KB11 | CAP CHIP 0.022U 16V(+-10%,X7R,0402) | ACER PERIPHERALS INC.(Darfon Electronics Corp.) Darfon Precisions(Suzhou)Co.,LTD | C1005X7R223KET | 3 | PC2000,PC2001,PC2002 |
| 136 | CH3474K1B04 | CAP CHIP 0.047U 25V(+-10% X7R 0402) | ACER PERIPHERALS INC.(Darfon Electronics Corp.) Darfon Precisions(Suzhou)Co.,LTD | C1005X7R473KFT | 12 | C110,C111,C112,C114,C115,C116,C117,C119,C120,C171,C173,C1316 |
| 138 | CH3474K1B04 | CAP CHIP 0.047U 25V(+-10% X7R 0402) | ACER PERIPHERALS INC.(Darfon Electronics Corp.) Darfon Precisions(Suzhou)Co.,LTD | C1005X7R473KFT | 1 | PC2193 |
| 142 | CH3683K1B09 | CAP CHIP 0.068UF 16V(+-10%,X7R 0402) | ACER PERIPHERALS INC.(Darfon Electronics Corp.) Darfon Precisions(Suzhou)Co.,LTD | C1005X7R683KET | 5 | PC2184,PC2185,PC2191,PC2226,PC2227 |
| 144 | CH4101KEE01 | CAP CHIP 0.1UF 6.3V(10%,X6S,0201,H0.3) | MURATA ERIE N.A. INC TAIWAN BRANCH Okayama Murata Mfg.Co.,Ltd.Wakura Murata Mfg. Co., Ltd. (Peregrine Semiconductor Corp) | GRM033C80J104K | 6 | C1096,C1097,C2289,C2290,C2291,C2292 |
| 145 | CH4104K1B00 | CAP CHIP 0.1U 25V(+-10%,X7R,0402) | MURATA ERIE N.A. INC TAIWAN BRANCH Okayama Murata Mfg.Co.,Ltd.Wakura Murata Mfg. Co., Ltd. (Peregrine Semiconductor Corp) | GRM155R71E104K | 251 | C174,C188,C204,C205,C206,C207,C210,C211,C537,C538,C539,C540,C543,C544,C548,C549,C552,C554,C559,C560,C561,C562,C567,C568,C569,C570,C578,C579,C580,C581,C592,C593,C607,C608,C609,C629,C639,C640,C641,C1122,C1150,C1173,C1175,C1233,C1234,C1235,C1236,C1237,C1238,C1239,C1240,C1274,C1275,C1278,C1279,C1282,C1283,C1288,C1292,C1305,C1317,C1320,C1321,C1322,C1323,C1325,C1337,C1592,C1613,C1614,C1619,C1647,C1663,C1664,C1707,C1713,C1751,C1766,C1769,C1770,C1775,C1796,C1797,C1803,C1809,C1810,C1817,C1818,C1819,C1820,C1821,C1822,C1823,C1824,C1825,C1826,C1827,C1831,C1832,C1833,C1834,C1835,C1836,C1837,C1838,C1839,C1840,C1841,C1859,C1860,C1861,C1862,C1873,C1874,C1875,C1876,C1877,C1878,C1879,C1880,C1882,C1886,C1889,C1905,C1906,C1907,C1923,C1924,C1925,C1941,C1942,C1943,C1944,C1945,C1946,C1947,C1957,C1958,C1963,C1977,C1979,C1997,C1998,C2010,C2012,C2013,C2014,C2015,C2017,C2018,C2019,C2020,C2021,C2022,C2024,C2027,C2056,C2067,C2069,C2071,C2249,C2252,C2253,C2254,C2257,C2258,C2259,C2274,C2275,C2276,C2283,C2285,C2286,C2329,C2330,C2333,C2334,C2335,C2336,C2337,C2338,C2339,C2341,C2344,C2345,C2346,C2347,C2348,C2360,C2376,C2377,C2378,C2394,C2444,PC221,PC330,PC386,PC390,PC474,PC548,PC577,PC624,PC628,PC1221,PC1224,PC1251,PC1254,PC1264,PC1267,PC1338,PC1339,PC1340,PC1341,PC1342,PC1343,PC1344,PC1345,PC1346,PC1347,PC1348,PC1349,PC1350,PC1351,PC1352,PC1354,PC1355,PC1356,PC1358,PC1359,PC1360,PC1361,PC1362,PC1363,PC1364,PC1365,PC1366,PC1367,PC1368,PC1369,PC1370,PC1371,PC1852,PC1853,PC1869,PC2091,PC2092,PC2137,PC2152,PC2217,PC2218,PC2238 |
| 146 | CH4104K1B00 | CAP CHIP 0.1U 25V(+-10%,X7R,0402) | MURATA ERIE N.A. INC TAIWAN BRANCH Okayama Murata Mfg.Co.,Ltd.Wakura Murata Mfg. Co., Ltd. (Peregrine Semiconductor Corp) | GRM155R71E104K | 2 | C1347,C1757 |
| 147 | CH4104K1B00 | CAP CHIP 0.1U 25V(+-10%,X7R,0402) | MURATA ERIE N.A. INC TAIWAN BRANCH Okayama Murata Mfg.Co.,Ltd.Wakura Murata Mfg. Co., Ltd. (Peregrine Semiconductor Corp) | GRM155R71E104K | 8 | C1863,C1864,C1865,C1866,C1868,C1869,C1870,C1871 |
| 148 | CH4104K1B00 | CAP CHIP 0.1U 25V(+-10%,X7R,0402) | MURATA ERIE N.A. INC TAIWAN BRANCH Okayama Murata Mfg.Co.,Ltd.Wakura Murata Mfg. Co., Ltd. (Peregrine Semiconductor Corp) | GRM155R71E104K | 5 | C2032,C2033,C2034,C2039,C2040 |
| 157 | CH4106K1B01 | CAP CHIP 100NF 50V(+-10%,X7R,0402) | ACER PERIPHERALS INC.(Darfon Electronics Corp.) Darfon Precisions(Suzhou)Co.,LTD | C1005X7R104KGT | 68 | C1042,C1172,C1227,C1332,C1339,C2179,C2449,C3271,PC178,PC181,PC193,PC194,PC199_P0_1,PC234,PC235,PC256,PC257,PC278,PC279,PC300,PC301,PC308_P0_1,PC376,PC379,PC401,PC402,PC431,PC434,PC446,PC447,PC452_P1_1,PC487,PC488,PC509,PC510,PC531,PC532,PC564,PC565,PC572_P1_1,PC606,PC607,PC612_P0_1,PC621_P1_1,PC636,PC639,PC1177,PC1178,PC1183_P0_4,PC1197,PC1198,PC1203_P1_4,PC1234,PC1236,PC1276,PC1284,PC1648,PC1649,PC1650,PC1651,PC1652,PC1653,PC1654,PC1655,PC1656,PC1657,PC1658,PC1659 |
| 161 | CH4221KEE00 | CAP CHIP 0.22UF 6.3V(+-10%,X6S,0201) | EYANG TECHNOLOGY DEVELOPMENT CO., LTD | C0201X6S224K6R3NTJ | 2 | C1436,C1437 |
| 162 | CH4221MEE01 | CAP CHIP 0.22UF 6.3V(20%,X6S,0201)_DIFF BUS | MURATA ERIE N.A. INC TAIWAN BRANCH Okayama Murata Mfg.Co.,Ltd.Wakura Murata Mfg. Co., Ltd. (Peregrine Semiconductor Corp) | C0603X6S0J224MT-A | 374 | C139,C141,C142,C143,C144,C145,C146,C147,C148,C149,C150,C151,C152,C153,C154,C155,C156,C157,C158,C159,C160,C161,C162,C163,C164,C165,C166,C167,C168,C169,C170,C678,C679,C680,C681,C682,C683,C684,C685,C686,C687,C688,C689,C690,C691,C692,C693,C694,C695,C696,C697,C698,C699,C700,C701,C702,C703,C704,C705,C706,C707,C708,C709,C710,C711,C712,C713,C714,C715,C716,C717,C718,C719,C720,C721,C722,C723,C724,C725,C726,C727,C728,C729,C730,C731,C732,C733,C734,C735,C736,C737,C738,C739,C740,C741,C742,C743,C744,C745,C746,C747,C748,C749,C750,C751,C752,C753,C754,C755,C756,C757,C758,C759,C760,C761,C762,C763,C764,C765,C766,C767,C768,C769,C770,C771,C772,C773,C806,C807,C808,C809,C810,C811,C812,C813,C814,C815,C816,C817,C818,C819,C820,C821,C822,C823,C824,C825,C826,C827,C828,C829,C830,C831,C832,C833,C834,C835,C836,C837,C838,C839,C840,C841,C842,C843,C844,C845,C846,C847,C848,C849,C850,C851,C852,C853,C854,C855,C856,C857,C858,C859,C860,C861,C862,C863,C864,C865,C866,C867,C868,C869,C870,C871,C872,C873,C874,C875,C876,C877,C878,C879,C880,C881,C882,C883,C884,C885,C886,C887,C888,C889,C890,C891,C892,C893,C894,C895,C896,C897,C898,C899,C900,C901,C902,C903,C904,C905,C906,C907,C908,C909,C910,C911,C912,C913,C914,C915,C916,C917,C918,C919,C920,C921,C922,C923,C924,C925,C926,C927,C928,C929,C930,C931,C932,C933,C934,C935,C936,C937,C938,C939,C940,C941,C942,C943,C944,C945,C946,C947,C948,C949,C950,C951,C952,C953,C954,C955,C956,C957,C958,C959,C960,C961,C962,C963,C964,C965,C1098,C1099,C1100,C1101,C1102,C1103,C1104,C1105,C1516,C1517,C1518,C1519,C1520,C1521,C1522,C1523,C1524,C1525,C1526,C1527,C1528,C1529,C1530,C1531,C1532,C1533,C1534,C1535,C1536,C1537,C1538,C1539,C1540,C1541,C1542,C1543,C1544,C1545,C1546,C1547,C1548,C1549,C1550,C1552,C1553,C1554,C1555,C1556,C1557,C1558,C1559,C1560,C1563,C1564,C1565,C1566,C1567,C1568,C1569,C1570,C1571,C1572,C1573,C1574,C1575,C1576,C1577,C1578,C1579,C1791,C1792,C1793,C1794,C1989,C1990,C1991,C1992,C1993,C1994,C1995,C1996,C2073,C2074,C2075,C2076,C2077,C2078 |
| 166 | CH4224K1B01 | CAP CHIP 0.22U 25V(10%,X7R,0402) | MURATA ERIE N.A. INC TAIWAN BRANCH Okayama Murata Mfg.Co.,Ltd.Wakura Murata Mfg. Co., Ltd. (Peregrine Semiconductor Corp) | GRM155R71E224K | 11 | C1226,C2359,C2541,PC568,PC1222,PC1235,PC1252,PC1265,PC1275,PC1283,PC1847 |
| 167 | CH4331KEB01 | CAP CHIP 0.33UF 6.3V(10%,X6S,0402)_FOR DIFF BUS | MURATA ERIE N.A. INC TAIWAN BRANCH Okayama Murata Mfg.Co.,Ltd.Wakura Murata Mfg. Co., Ltd. (Peregrine Semiconductor Corp) | GRM155C80J334K | 2 | C2349,C2350 |
| 168 | CH5103KEB01 | CAP CHIP 1UF 16V(10%,X6S,0402) | MURATA ERIE N.A. INC TAIWAN BRANCH Okayama Murata Mfg.Co.,Ltd.Wakura Murata Mfg. Co., Ltd. (Peregrine Semiconductor Corp) | GRM155C81C105K | 62 | PC177,PC191_P0_1,PC192_P0_2,PC225,PC232_P0_8,PC233_P0_7,PC242_P0_8,PC243_P0_7,PC254_P0_6,PC255_P0_5,PC276_P0_4,PC277_P0_3,PC298_P0_2,PC299_P0_1,PC310_P0_1,PC337,PC375,PC394,PC399_P1_1,PC400_P1_2,PC408_P1_2,PC430,PC444_P1_1,PC445_P1_2,PC478,PC485_P1_8,PC486_P1_7,PC495_P1_8,PC496_P1_7,PC507_P1_6,PC508_P1_5,PC529_P1_4,PC530_P1_3,PC555,PC562_P1_2,PC563_P1_1,PC574_P1_1,PC604_P0_1,PC605_P0_2,PC613_P0_2,PC632,PC635,PC813,PC814,PC1173,PC1175_P0_3,PC1176_P0_4,PC1183_P0_3,PC1193,PC1194,PC1195_P1_3,PC1196,PC1196_P1_4,PC1204_P1_3,PC1219,PC1249,PC1262,PC1274,PC1282,PC1289,PC1372,PC1846 |
| 169 | CH5104KEB02 | CAP CHIP 1UF 25V(+-10%,X6S,0402) | MURATA ERIE N.A. INC TAIWAN BRANCH Okayama Murata Mfg.Co.,Ltd.Wakura Murata Mfg. Co., Ltd. (Peregrine Semiconductor Corp) | GRM155C81E105K | 42 | C107,C541,C542,C545,C546,C547,C550,C551,C605,C606,C610,C611,C1177,C1289,C1290,C1291,C1293,C1311,C1312,C1315,C1319,C1561,C1612,C1884,C2007,C2243,C2246,C2247,C2248,PC113,PC644,PC1642,PC1848,PC2079,PC2139,PC2140,PC2207,PC2221,PC2222,PC2230,PC2643,PC5328 |
| 170 | CH5104KEB02 | CAP CHIP 1UF 25V(+-10%,X6S,0402) | MURATA ERIE N.A. INC TAIWAN BRANCH Okayama Murata Mfg.Co.,Ltd.Wakura Murata Mfg. Co., Ltd. (Peregrine Semiconductor Corp) | GRM155C81E105K | 3 | C2031,C2035,C2041 |
| 173 | CH5104KEB02 | CAP CHIP 1UF 25V(+-10%,X6S,0402) | MURATA ERIE N.A. INC TAIWAN BRANCH Okayama Murata Mfg.Co.,Ltd.Wakura Murata Mfg. Co., Ltd. (Peregrine Semiconductor Corp) | GRM155C81E105K | 8 | PC1525,PC2103,PC2181,PC2186,PC2187,PC2188,PC2223,PC3272 |
| 174 | CH5104KEB02 | CAP CHIP 1UF 25V(+-10%,X6S,0402) | MURATA ERIE N.A. INC TAIWAN BRANCH Okayama Murata Mfg.Co.,Ltd.Wakura Murata Mfg. Co., Ltd. (Peregrine Semiconductor Corp) | GRM155C81E105K | 4 | PC190,PC2086,PC2093,PC2147 |
| 180 | CH5104KEB02 | CAP CHIP 1UF 25V(+-10%,X6S,0402) | MURATA ERIE N.A. INC TAIWAN BRANCH Okayama Murata Mfg.Co.,Ltd.Wakura Murata Mfg. Co., Ltd. (Peregrine Semiconductor Corp) | GRM155C81E105K | 3 | PC2208,PC2210,PC2212 |
| 183 | CH5104KEB02 | CAP CHIP 1UF 25V(+-10%,X6S,0402) | MURATA ERIE N.A. INC TAIWAN BRANCH Okayama Murata Mfg.Co.,Ltd.Wakura Murata Mfg. Co., Ltd. (Peregrine Semiconductor Corp) | GRM155C81E105K | 2 | PC2233,PC2234 |
| 184 | CH5221MEB00 | CAP CHIP 2.2U 6.3V(+-20%,X6S,0402) | Matsuki Precision Ceramic Co., Ltd.Matsuki Polymer Technology Co., Ltd. | MAG02X6S0J225M | 32 | C2,C5,C8,C11,C14,C17,C20,C23,C26,C29,C32,C35,C38,C41,C44,C47,C50,C53,C56,C59,C62,C65,C68,C72,C75,C78,C81,C84,C87,C90,C93,C96 |
| 185 | CH5222KEB01 | CAP CHIP 2.2UF 10V(+-10%,X6S,0402) | MURATA ERIE N.A. INC TAIWAN BRANCH Okayama Murata Mfg.Co.,Ltd.Wakura Murata Mfg. Co., Ltd. (Peregrine Semiconductor Corp) | GRM155C81A225K | 68 | C1183,C1189,C1200,C1204,C1214,C1242,PC175,PC187,PC188,PC226,PC227,PC228_P0_8,PC229_P0_7,PC248,PC249,PC250_P0_6,PC251_P0_5,PC270,PC271,PC272_P0_4,PC273_P0_3,PC292,PC293,PC294_P0_2,PC295_P0_1,PC373,PC395,PC396,PC428,PC440,PC441,PC479,PC480,PC481_P1_8,PC482_P1_7,PC501,PC502,PC503_P1_6,PC504_P1_5,PC523,PC524,PC525_P1_4,PC526_P1_3,PC556,PC557,PC558_P1_2,PC559_P1_1,PC600,PC601,PC633,PC1171,PC1172,PC1191,PC1192,PC1211_P0_1,PC1212_P0_2,PC1213_P0_3,PC1214_P0_4,PC1242_P1_1,PC1243_P1_2,PC1244_P1_3,PC1245_P1_4,PC2946,PC2947,PC2948,PC2949,PC2950,PC2951 |
| 186 | CH5223KE901 | CAP CHIP 2.2U 16V(+-10%,X6S,0603) | MURATA ERIE N.A. INC TAIWAN BRANCH Okayama Murata Mfg.Co.,Ltd.Wakura Murata Mfg. Co., Ltd. (Peregrine Semiconductor Corp) | GRM188C81C225K | 1 | PC591 |
| 190 | CH5473KE902 | CAP CHIP 4.7UF 16V(+-10%,X6S,0603) | MURATA ERIE N.A. INC TAIWAN BRANCH Okayama Murata Mfg.Co.,Ltd.Wakura Murata Mfg. Co., Ltd. (Peregrine Semiconductor Corp) | GRM188C81C475K | 2 | PC8,PC581 |
| 191 | CH6101ME900 | CAP CHIP 10U 6.3V(+-20%,X6S,0603) | KYOCERA CORPORATION | CM105X6S106M06AT | 18 | C108,C172,C208,C209,C1251,C1252,C1254,C1255,C1260,C1261,C1309,C1310,C1313,C1314,C1409,C2328,C2331,C2332 |
| 192 | CH6101MEB01 | CAP CHIP 10UF 6.3V(+-20%,X6S,0402) | MURATA ERIE N.A. INC TAIWAN BRANCH Okayama Murata Mfg.Co.,Ltd.Wakura Murata Mfg. Co., Ltd. (Peregrine Semiconductor Corp) | GRM155C80J106M | 19 | C1,C71,C1203,C1205,C1206,C1207,C1210,C1228,C1231,C1262,C1263,C1266,C1842,C1935,C1936,C1937,C1938,C1939,C1940 |
| 193 | CH6101MEB01 | CAP CHIP 10UF 6.3V(+-20%,X6S,0402) | MURATA ERIE N.A. INC TAIWAN BRANCH Okayama Murata Mfg.Co.,Ltd.Wakura Murata Mfg. Co., Ltd. (Peregrine Semiconductor Corp) | GRM155C80J106M | 1 | C2038 |
| 194 | CH6101MEB03 | CAP CHIP 10UF 6.3V(+-20%,X6S,0402)MUR | MURATA ERIE N.A. INC TAIWAN BRANCH Okayama Murata Mfg.Co.,Ltd.Wakura Murata Mfg. Co., Ltd. (Peregrine Semiconductor Corp) | GRM155C80J106M | 88 | C221,C222,C223,C224,C226,C227,C228,C229,C231,C232,C233,C234,C236,C237,C238,C239,C241,C242,C243,C244,C246,C247,C248,C249,C251,C252,C253,C254,C256,C257,C258,C259,C261,C262,C263,C264,C266,C267,C268,C269,C966,C967,C968,C969,C970,C971,C972,C973,C974,C975,C976,C977,C978,C979,C980,C981,C982,C983,C984,C985,C986,C987,C988,C989,C990,C991,C992,C993,C994,C995,C996,C997,C998,C999,C1000,C1001,C1002,C1003,C1004,C1005,C1336,C2443,PC224,PC335,PC392,PC477,PC553,PC630 |
| 195 | CH6103KEA00 | CAP CHIP 10UF 16V(+-10%,X6S,0805) | MURATA ERIE N.A. INC TAIWAN BRANCH Okayama Murata Mfg.Co.,Ltd.Wakura Murata Mfg. Co., Ltd. (Peregrine Semiconductor Corp) | GRM21BC81C106K | 68 | C3,C4,C6,C7,C9,C10,C12,C13,C15,C16,C18,C19,C21,C22,C24,C25,C27,C28,C30,C31,C33,C34,C36,C37,C39,C40,C42,C43,C45,C46,C48,C49,C51,C52,C54,C55,C57,C58,C60,C61,C63,C64,C66,C67,C69,C70,C73,C74,C76,C77,C79,C80,C82,C83,C85,C86,C88,C89,C91,C92,C94,C95,C97,C98,C1170,C1331,C1333,C1340 |
| 196 | CH6103KEA00 | CAP CHIP 10UF 16V(+-10%,X6S,0805) | MURATA ERIE N.A. INC TAIWAN BRANCH Okayama Murata Mfg.Co.,Ltd.Wakura Murata Mfg. Co., Ltd. (Peregrine Semiconductor Corp) | GRM21BC81C106K | 2 | C1767,C1768 |
| 198 | CH6103KEA01 | CAP CHIP 10UF 16V(+-10%,X6S,0805)MUR | MURATA ERIE N.A. INC TAIWAN BRANCH Okayama Murata Mfg.Co.,Ltd.Wakura Murata Mfg. Co., Ltd. (Peregrine Semiconductor Corp) | GRM21BC81C106K | 5 | PC1232,PC1233,PC2081,PC2142,PC2220 |
| 201 | CH6103KEA03 | CAP CHIP 10UF 16V(+-10%,X6S,0805)SAM | SAMSUNG ELECTRONICS CO.,LTD (Samsung Mobile Display)SAMSUNG SDI CO.,LTD | CL21X106KOQNNNE | 5 | PC2082,PC2143,PC2219,PC2240,PC2280 |
| 202 | CH6104KEA00 | CAP CHIP 10U 25V(+-10%,X6S,0805,H1.25) | Matsuki Precision Ceramic Co., Ltd.Matsuki Polymer Technology Co., Ltd. | MAG05X6S1E106K | 1 | C1867 |
| 203 | CH6104KEA00 | CAP CHIP 10U 25V(+-10%,X6S,0805,H1.25) | Matsuki Precision Ceramic Co., Ltd.Matsuki Polymer Technology Co., Ltd. | MAG05X6S1E106K | 2 | C563,C1883 |
| 204 | CH6221ME900 | CAP CHIP 22U 6.3V(+-20%,X6S,0603) | ACER PERIPHERALS INC.(Darfon Electronics Corp.) Darfon Precisions(Suzhou)Co.,LTD | C1608X6S226MCT | 6 | C1184,C1191,C1201,C1920,C1921,C1922 |
| 205 | CH6222MEA01 | CAP CHIP 22U 10V(+-20%,X6S,0805)MUR | MURATA ERIE N.A. INC TAIWAN BRANCH Okayama Murata Mfg.Co.,Ltd.Wakura Murata Mfg. Co., Ltd. (Peregrine Semiconductor Corp) | GRM21BC81A226M | 5 | PC1599,PC1600,PC1855,PC1856,PC1868 |
| 206 | CH6223MEA00 | CAP CHIP 22U 16V(+-20%,X6S,0805) | MURATA ERIE N.A. INC TAIWAN BRANCH Okayama Murata Mfg.Co.,Ltd.Wakura Murata Mfg. Co., Ltd. (Peregrine Semiconductor Corp) | GRM21BC81C226M | 5 | C1213,C1232,C1829,C1830,C2284 |
| 207 | CH6223MEA01 | CAP CHIP 22UF 16V(+-20%,X6S,0805)MUR | MURATA ERIE N.A. INC TAIWAN BRANCH Okayama Murata Mfg.Co.,Ltd.Wakura Murata Mfg. Co., Ltd. (Peregrine Semiconductor Corp) | GRM21BC81C226M | 136 | C513,C535,C1276,C1277,PC71,PC179,PC180,PC195_P0_1,PC196_P0_2,PC197_P0_1,PC198_P0_2,PC236_P0_8,PC237_P0_7,PC238_P0_8,PC239_P0_7,PC240_P0_8,PC241_P0_7,PC258_P0_6,PC259_P0_5,PC260_P0_6,PC261_P0_5,PC262_P0_6,PC263_P0_5,PC280_P0_4,PC281_P0_3,PC282_P0_4,PC283_P0_3,PC284_P0_4,PC285_P0_3,PC302_P0_2,PC303_P0_1,PC304_P0_2,PC305_P0_1,PC306_P0_2,PC307_P0_1,PC377,PC378,PC403_P1_1,PC404_P1_2,PC405_P1_1,PC406_P1_2,PC432,PC433,PC448_P1_1,PC449_P1_2,PC450_P1_1,PC451_P1_2,PC489_P1_8,PC490_P1_7,PC491_P1_8,PC492_P1_7,PC493_P1_8,PC494_P1_7,PC511_P1_6,PC512_P1_5,PC513_P1_6,PC514_P1_5,PC515_P1_6,PC516_P1_5,PC533_P1_4,PC534_P1_3,PC535_P1_4,PC536_P1_3,PC537_P1_4,PC538_P1_3,PC566_P1_2,PC567,PC567_P1_1,PC568_P1_2,PC569_P1_1,PC570,PC570_P1_2,PC571,PC571_P1_1,PC576,PC608_P0_1,PC609_P0_2,PC610_P0_1,PC611_P0_2,PC637,PC638,PC720_P0_1,PC721_P0_2,PC722_P0_3,PC723_P0_4,PC724_P1_1,PC725_P1_2,PC726_P1_3,PC727_P1_4,PC831,PC1179_P0_3,PC1180_P0_4,PC1181_P0_3,PC1182_P0_4,PC1199_P1_3,PC1200_P1_4,PC1201_P1_3,PC1202_P1_4,PC1216,PC1217,PC1218,PC1247,PC1248,PC1259,PC1260,PC1261,PC1272,PC1273,PC1280,PC1281,PC1669,PC1670,PC1671,PC1672,PC1673,PC1674,PC1675,PC1676,PC1677,PC1678,PC1679,PC1680,PC1681,PC1682,PC1683,PC1684,PC1849,PC1850,PC1898,PC2260,PC2261,PC2262,PC2263,PC2342,PC2343,PC2344 |
| 208 | CH6223MEA03 | CAP CHIP 22U 16V(20%,X6S,0805)SAM | SAMSUNG ELECTRONICS CO.,LTD (Samsung Mobile Display)SAMSUNG SDI CO.,LTD | CL21X226MOYNNWE | 3 | PC2080,PC2141,PC2242 |
| 209 | CH622KME901 | CAP CHIP 22UF 4V(+-20%,X6S,0603) | MURATA ERIE N.A. INC TAIWAN BRANCH Okayama Murata Mfg.Co.,Ltd.Wakura Murata Mfg. Co., Ltd. (Peregrine Semiconductor Corp) | GRM188C80G226M | 10 | C1178,C1181,C1182,C1185,C1186,C1187,C1192,C1197,C1198,C1202 |
| 210 | CH622KMEA03 | CAP CHIP 22U 4V(+-20%,X6S,0805)MUR | MURATA ERIE N.A. INC TAIWAN BRANCH Okayama Murata Mfg.Co.,Ltd.Wakura Murata Mfg. Co., Ltd. (Peregrine Semiconductor Corp) | GRM21BC80G226M | 85 | PC1,PC2,PC184,PC186,PC202_P0_1,PC203_P0_2,PC204_P0_1,PC205_P0_2,PC244_P0_8,PC245_P0_7,PC246_P0_8,PC247_P0_7,PC266_P0_6,PC267_P0_5,PC268_P0_6,PC269_P0_5,PC288_P0_4,PC289_P0_3,PC290_P0_4,PC291_P0_3,PC311_P0_2,PC312_P0_1,PC313_P0_2,PC314_P0_1,PC381,PC382,PC410_P1_1,PC411_P1_2,PC412_P1_1,PC413_P1_2,PC435,PC437,PC455_P1_1,PC456_P1_2,PC457_P1_1,PC458_P1_2,PC497_P1_8,PC498_P1_7,PC499_P1_8,PC500_P1_7,PC519_P1_6,PC520_P1_5,PC521_P1_6,PC522_P1_5,PC541_P1_4,PC542_P1_3,PC543_P1_4,PC544_P1_3,PC575_P1_2,PC576_P1_1,PC577_P1_2,PC578_P1_1,PC615_P0_1,PC616_P0_2,PC617_P0_1,PC618_P0_2,PC641,PC642,PC1185_P0_3,PC1186_P0_4,PC1187_P0_3,PC1188_P0_4,PC1206,PC1206_P1_3,PC1207,PC1207_P1_4,PC1208_P1_3,PC1209_P1_4,PC1237,PC1238,PC1239,PC1240,PC1241,PC1255,PC1256,PC1257,PC1268,PC1269,PC1270,PC1277,PC1278,PC1279,PC1285,PC1286,PC1287 |
| 211 | CH622KMEB01 | CAP CHIP 22UF 4V(+-20%,X6S,0402)MUR | MURATA ERIE N.A. INC TAIWAN BRANCH Okayama Murata Mfg.Co.,Ltd.Wakura Murata Mfg. Co., Ltd. (Peregrine Semiconductor Corp) | GRM158C80G226M | 137 | C271,C272,C273,C274,C275,C276,C277,C278,C279,C280,C281,C282,C283,C284,C285,C286,C287,C288,C289,C290,C291,C292,C293,C294,C295,C296,C297,C298,C299,C300,C301,C302,C303,C304,C305,C306,C307,C308,C309,C310,C399,C400,C401,C402,C403,C404,C405,C406,C407,C408,C409,C410,C411,C412,C413,C414,C415,C416,C417,C418,C419,C420,C421,C422,C423,C424,C425,C426,C427,C428,C429,C430,C431,C432,C433,C434,C435,C436,C437,C438,C439,C440,C441,C442,C443,C444,C445,C446,C490,C534,C590,C1006,C1007,C1008,C1009,C1010,C1011,C1012,C1013,C1014,C1015,C1016,C1017,C1018,C1019,C1020,C1021,C1022,C1023,C1024,C1025,C1026,C1027,C1028,C1029,C1030,C1031,C1032,C1033,C1034,C1035,C1036,C1037,C1038,C1039,C1040,C1041,C1043,C1044,C1045,C1302,C1353,C1362,C1363,C1364,C1365,C1366 |
| 212 | CH6471MEA02 | CAP CHIP 47U 6.3V(+-20%,X6S,0805) | MURATA ERIE N.A. INC TAIWAN BRANCH Okayama Murata Mfg.Co.,Ltd.Wakura Murata Mfg. Co., Ltd. (Peregrine Semiconductor Corp) | GRM21BC80J476M | 2 | C1243,C1245 |
| 213 | CH647KMEA04 | CAP CHIP 47U 4V(+-20%,X6S,0805)MUR | MURATA ERIE N.A. INC TAIWAN BRANCH Okayama Murata Mfg.Co.,Ltd.Wakura Murata Mfg. Co., Ltd. (Peregrine Semiconductor Corp) | GRM21BC80G476M | 195 | C101,C212,C213,C214,C215,C216,C217,C218,C219,C220,C225,C230,C235,C240,C245,C250,C255,C260,C265,C270,C311,C312,C313,C314,C315,C316,C317,C318,C320,C321,C322,C323,C324,C325,C326,C327,C328,C329,C330,C332,C333,C335,C336,C337,C338,C339,C341,C342,C343,C344,C345,C346,C347,C348,C349,C350,C351,C352,C353,C354,C355,C356,C357,C358,C359,C360,C361,C362,C363,C364,C365,C366,C367,C368,C369,C370,C371,C372,C373,C374,C376,C377,C379,C380,C381,C382,C383,C385,C386,C387,C388,C389,C390,C391,C392,C393,C394,C395,C396,C397,C398,C447,C448,C449,C450,C451,C452,C453,C454,C455,C456,C457,C458,C459,C460,C461,C462,C463,C464,C466,C467,C468,C470,C471,C473,C474,C476,C477,C478,C479,C481,C482,C483,C484,C485,C486,C487,C491,C492,C493,C494,C495,C496,C497,C498,C499,C500,C501,C502,C503,C504,C505,C506,C507,C508,C510,C511,C512,C514,C515,C517,C518,C520,C521,C522,C523,C525,C526,C527,C528,C529,C530,C531,C1244,C1246,C1247,C1248,C1249,C1258,C1259,C1272,C1273,C1387,C1388,C1390,C1392,C1396,C1397,C1398,C1399,C1400,C1403,C1404,PC1225,PC1226 |
| 214 | CH647LME900 | CAP CHIP 47U 2.5V(+-20%,X6S,0603)MUR | MURATA ERIE N.A. INC TAIWAN BRANCH Okayama Murata Mfg.Co.,Ltd.Wakura Murata Mfg. Co., Ltd. (Peregrine Semiconductor Corp) | GRM188C80E476M | 16 | C465,C472,C475,C488,C489,C509,C516,C519,C532,C533,C1389,C1391,C1393,C1405,C1406,C1407 |
| 215 | CH733LY8802 | CAPCHIP 330U 2.5V(10/-35%,SPCAP,7343)MAT | MATSUSHITA ELECTRONICS CORPORATION (PANASONIC)Wuxi Matsushita Battery Co., Ltd (Panasonic Communicat......(Skip) | EEFSX0E331EY | 10 | PC418,PC623,PC1187,PC1205,PC1900,PC1930,PC2170,PC2171,PC2172,PC2645 |
| 216 | CH733RY8807 | CAP CHIP 330U 2V(+10-35%,SPCAP,7343)MAT | MATSUSHITA ELECTRONICS CORPORATION (PANASONIC)Wuxi Matsushita Battery Co., Ltd (Panasonic Communication Corp. of the Phils) Panasonic Precision Devices Co.,Ltd. | EEFSX0D331YR | 8 | PC117,PC1229,PC1573,PC1575,PC1588,PC1594,PC1910,PC1940 |
| 217 | CS+001DFR10 | RES CHIP 0.001 3W +-1%(2512)RLC_4P | RALEC ELECTRONIC CO. | LR2512-23R001F4 | 2 | R1837,R1838 |
| 219 | CS+0108F128 | RES CHIP 0.01 1W +-1%(2512) | CYNTEC CO., LTD. | RL32646-R010-FN | 5 | R3633,R3634,R3635,R3645,R3767 |
| 220 | CS-1002FB04 | RES CHIP 1 1/16W +-1%(0402)EF | CYNTEC CO., LTD. | RR0510S-1R0-FTF | 8 | PR130,PR176,PR220,PR283,PR323,PR375,PR389,R4077 |
| 222 | CS-1003F900 | RES CHIP 1 1/10W +-1%(0603)EF | RALEC ELECTRONIC CO. | FTT031R00FTP | 12 | R442,R447,R519,R3344,R3345,R3346,R3347,R3348,R3349,R3458,R4475,R4493 |
| 223 | CS-2202FB01 | RES CHIP 2.2 1/16W +-1%(0402)EF | CYNTEC CO., LTD. | RR0510S-2R2-FTF | 32 | PR97,PR101,PR102,PR134,PR135,PR140,PR141,PR146,PR147,PR152,PR153,PR200,PR226,PR227,PR250,PR254,PR255,PR287,PR288,PR293,PR294,PR299,PR300,PR327,PR328,PR355,PR356,PR380,PR1299,PR1300,PR1306,PR1307 |
| 224 | CS-2203F902 | RES CHIP 2.2 1/10W +-1%(0603)EF | RALEC ELECTRONIC CO. | FTT032R20FTP | 2 | R571,R572 |
| 225 | CS-3302FB01 | RES CHIP 3.3 1/16W +-1%(0402)EF | WALSIN TECHNOLOGY CORPORATION | WR04W3R30FTR | 34 | PR1,PR2,PR1766,PR1767,PR1768,PR1769,PR1770,PR1771,PR1772,PR1773,PR1774,PR1775,PR1778,PR1780,PR1781,PR1782,PR1783,PR1784,PR1786,PR1787,PR1788,PR1789,PR1790,PR1791,PR1792,PR1793,PR1794,PR1795,PR1798,PR1800,PR1801,PR1802,PR1803,PR1804 |
| 226 | CS-5102JB02 | RES CHIP 5.1 1/16W +-5%(0402)EF | CYNTEC CO., LTD. | RR0510S-5R1-JTF | 1 | PR1329 |
| 227 | CS00002JB13 | RES CHIP 0 1/16W +-5%(0402)EF | CYNTEC CO., LTD. | RR0510S-000-XTF | 517 | PR108,PR120,PR121,PR136,PR137,PR142,PR143,PR148,PR149,PR154,PR155,PR156,PR158,PR170,PR171,PR216,PR242,PR261,PR273,PR274,PR275,PR289,PR290,PR295,PR296,PR301,PR302,PR303,PR305,PR317,PR329,PR330,PR338,PR345,PR371,PR395,PR402,PR442,PR444,PR447,PR639,PR678,PR701,PR702,PR832,PR835,PR1311,PR1315,PR1322,PR1323,PR1324,PR1325,PR1326,PR1331,PR1332,PR1333,PR1334,PR1335,PR1338,PR1776,PR1777,PR1779,PR1785,PR1796,PR1797,PR1799,PR1805,PR3002,PR3337,PR3338,PR3339,PR4220,PR4221,PR4222,PR4223,PR4224,PR4225,PR4230,PR4231,PR4232,PR4233,PR4234,PR4235,PR4236,PR4242,PR4243,PR4244,PR4245,PR4246,PR4251,PR4252,PR4253,PR4254,PR4255,PR4256,PR4257,PR4271,PR4272,PR4683,PR4699,R12,R13,R15,R16,R20,R21,R55,R56,R58,R59,R122,R124,R126,R128,R130,R132,R142,R144,R149,R160,R162,R164,R166,R168,R171,R188,R208,R210,R239,R240,R297,R299,R302,R304,R308,R309,R311,R312,R336,R337,R338,R340,R341,R342,R344,R345,R346,R362,R363,R365,R416,R417,R418,R429,R444,R445,R480,R481,R482,R483,R486,R506,R553,R554,R593,R594,R595,R596,R597,R598,R599,R600,R670,R672,R674,R676,R687,R689,R691,R693,R700,R737,R738,R746,R762,R764,R765,R815,R816,R817,R818,R835,R836,R837,R838,R851,R852,R853,R854,R859,R860,R861,R915,R916,R917,R918,R998,R999,R1010,R1011,R1012,R1014,R1016,R1018,R1020,R1021,R1022,R1023,R1139,R1147,R1148,R1184,R1214,R1240,R1247,R1249,R1294,R1295,R1296,R1297,R1318,R1345,R1348,R1349,R1389,R1461,R1463,R1464,R1525,R1543,R1547,R1640,R1650,R1652,R1671,R1680,R1721,R1724,R1744,R1748,R1798,R1801,R1815,R1816,R1821,R1853,R1944,R1950,R1959,R1960,R2114,R2155,R2208,R2209,R2210,R2211,R2255,R2268,R2313,R2316,R2347,R2348,R2350,R2358,R2360,R2366,R2369,R2370,R2376,R2379,R2380,R2387,R2388,R2389,R2390,R2391,R2394,R2397,R2400,R2401,R2402,R2403,R2405,R2408,R2412,R2413,R2414,R2415,R2416,R2452,R2513,R2520,R2521,R2523,R2526,R2529,R2531,R2550,R2552,R2557,R2558,R2560,R2561,R2562,R2563,R2565,R2566,R2570,R2572,R2574,R2576,R2577,R2579,R2580,R2582,R2591,R2594,R2595,R2597,R2659,R2660,R2676,R2703,R2704,R2706,R2707,R2725,R2792,R2802,R2803,R2848,R2899,R2905,R2906,R2922,R2967,R2968,R2969,R2971,R2982,R2983,R2992,R2994,R3023,R3033,R3045,R3046,R3047,R3048,R3049,R3051,R3066,R3067,R3103,R3105,R3106,R3107,R3108,R3109,R3110,R3111,R3123,R3124,R3125,R3126,R3142,R3143,R3168,R3169,R3170,R3171,R3172,R3177,R3178,R3233,R3236,R3237,R3244,R3263,R3264,R3294,R3303,R3304,R3305,R3306,R3307,R3308,R3326,R3327,R3335,R3336,R3337,R3338,R3352,R3353,R3354,R3355,R3393,R3394,R3441,R3442,R3443,R3499,R3516,R3517,R3518,R3526,R3527,R3559,R3560,R3561,R3563,R3580,R3581,R3620,R3636,R3637,R3710,R3713,R3714,R3715,R3716,R3717,R3718,R3719,R3720,R3721,R3722,R3751,R3752,R3770,R3772,R3775,R3776,R3777,R3778,R3779,R3924,R3996,R4056,R4060,R4064,R4075,R4076,R4088,R4177,R4212,R4213,R4214,R4215,R4216,R4268,R4305,R4306,R4460,R4461,R4467,R4468,R4473,R4474,R4501,R4503,R4504,R4511,R4513,R4531,R4534,R4593,R4594,R4595,R4599,R4600,R4601,R4602,R4606,R4607,R4624,R4626,R4627,R4628,R4629,R4630,R4631,R4632,R4633,R4695,R4696,R4697,R4720,R4721,R4728,R4729,R4734,R4735,R4736,R4741,R4742,R4752,R4753,R4780,R4781,R4802,R4803,R5234,R5236,R5377,R5487 |
| 228 | CS00002JB13 | RES CHIP 0 1/16W +-5%(0402)EF | CYNTEC CO., LTD. | RR0510S-000-XTF | 21 | PR2149,PR3910,PR3911,PR3916,PR3917,PR3919,PR3920,PR3921,PR3922,PR3928,PR3930,PR3980,PR3981,PR3988,PR3989,PR3992,PR3993,PR3994,PR3995,R1714,R2586 |
| 229 | CS00002JB13 | RES CHIP 0 1/16W +-5%(0402)EF | CYNTEC CO., LTD. | RR0510S-000-XTF | 4 | PR4012,R3997,R4062,R4708 |
| 230 | CS00002JB13 | RES CHIP 0 1/16W +-5%(0402)EF | CYNTEC CO., LTD. | RR0510S-000-XTF | 7 | R1792,R1793,R3679,R3681,R3683,R3685,R3687 |
| 231 | CS00002JB13 | RES CHIP 0 1/16W +-5%(0402)EF | CYNTEC CO., LTD. | RR0510S-000-XTF | 7 | R2786,R2787,R3651,R3652,R3655,R3662,R3666 |
| 237 | CS00002JB13 | RES CHIP 0 1/16W +-5%(0402)EF | CYNTEC CO., LTD. | RR0510S-000-XTF | 4 | R3785,R3794,R3807,R3832 |
| 238 | CS00002JB13 | RES CHIP 0 1/16W +-5%(0402)EF | CYNTEC CO., LTD. | RR0510S-000-XTF | 1 | R3859 |
| 242 | CS00002JB13 | RES CHIP 0 1/16W +-5%(0402)EF | CYNTEC CO., LTD. | RR0510S-000-XTF | 3 | R3863,R3867,R3869 |
| 246 | CS00002JB13 | RES CHIP 0 1/16W +-5%(0402)EF | CYNTEC CO., LTD. | RR0510S-000-XTF | 2 | R3939,R3974 |
| 253 | CS00002JB13 | RES CHIP 0 1/16W +-5%(0402)EF | CYNTEC CO., LTD. | RR0510S-000-XTF | 3 | R3959,R3973,R4063 |
| 255 | CS00002JB13 | RES CHIP 0 1/16W +-5%(0402)EF | CYNTEC CO., LTD. | RR0510S-000-XTF | 5 | R4537,R4659,R4660,R4663,R4664 |
| 259 | CS00004JA05 | RES CHIP 0 1/8W +-5% (0805)EF | RALEC ELECTRONIC CO. | FTT05000JTP | 1 | R1747 |
| 260 | CS00007T200 | RES CHIP 0 1/2W (1206)EF | DALE ELECTRONICS,INC. | WSL120600000ZEA9 | 2 | R324,R330 |
| 263 | CS01002FB07 | RES CHIP 10 1/16W +-1%(0402)EF | CYNTEC CO., LTD. | RR0510S-100-FTF | 2 | PR3782,PR3798 |
| 266 | CS01002FB07 | RES CHIP 10 1/16W +-1%(0402)EF | CYNTEC CO., LTD. | RR0510S-100-FTF | 1 | PR3967 |
| 267 | CS01002FB07 | RES CHIP 10 1/16W +-1%(0402)EF | CYNTEC CO., LTD. | RR0510S-100-FTF | 1 | PR4003 |
| 268 | CS01002FB07 | RES CHIP 10 1/16W +-1%(0402)EF | CYNTEC CO., LTD. | RR0510S-100-FTF | 34 | R1,R24,R25,R53,R54,R61,R752,R753,R754,R755,R756,R763,R775,R777,R1479,R1868,R1869,R1870,R1871,R1872,R2363,R3570,R3571,R3574,R3575,R3578,R3579,R3602,R3603,R3758,R3760,R4118,R4535,R4536 |
| 269 | CS02202FB02 | RES CHIP 22 1/16W +-1%(0402)EF | CYNTEC CO., LTD. | RR0510S-220-FTF | 21 | R563,R564,R565,R566,R1273,R1274,R1275,R1276,R1291,R1292,R1293,R3194,R3195,R3196,R3197,R3198,R3199,R3200,R3201,R4303,R4304 |
| 270 | CS02202FB02 | RES CHIP 22 1/16W +-1%(0402)EF | CYNTEC CO., LTD. | RR0510S-220-FTF | 2 | R2588,R3934 |
| 271 | CS02202JB09 | RES CHIP 22 1/16W +-5%(0402)EF | CYNTEC CO., LTD. | RR0510S-220-JTF | 1 | R2339 |
| 272 | CS02742FB03 | RES CHIP 27.4 1/16W +-1%(0402)EF | CYNTEC CO., LTD. | RR0510S-27R4-FTF | 4 | R1140,R1141,R2674,R3181 |
| 273 | CS03322FB03 | RES CHIP 33.2 1/16W +-1%(0402)EF | CYNTEC CO., LTD. | WR04X33R2FTR | 389 | R3,R7,R10,R11,R63,R67,R68,R107,R108,R109,R110,R113,R269,R315,R322,R419,R424,R425,R435,R474,R499,R501,R577,R578,R579,R580,R581,R582,R588,R589,R671,R673,R675,R677,R688,R690,R692,R694,R697,R699,R745,R803,R804,R805,R806,R880,R884,R885,R886,R889,R890,R893,R894,R895,R896,R897,R898,R899,R900,R901,R902,R903,R905,R906,R907,R908,R909,R960,R961,R962,R981,R982,R983,R984,R985,R986,R987,R988,R993,R994,R995,R996,R1100,R1130,R1131,R1205,R1206,R1207,R1263,R1268,R1300,R1306,R1307,R1309,R1310,R1313,R1395,R1423,R1442,R1443,R1444,R1446,R1447,R1448,R1469,R1470,R1472,R1504,R1505,R1514,R1520,R1526,R1594,R1595,R1600,R1606,R1656,R1657,R1661,R1662,R1693,R1719,R1736,R1751,R1752,R1753,R1754,R1755,R1756,R1757,R1758,R1811,R1812,R1827,R1843,R1844,R1919,R1921,R1932,R1933,R1934,R1935,R1995,R1996,R2113,R2362,R2371,R2372,R2410,R2411,R2417,R2418,R2419,R2420,R2421,R2422,R2423,R2424,R2425,R2449,R2450,R2453,R2454,R2455,R2456,R2477,R2478,R2479,R2480,R2489,R2498,R2499,R2500,R2501,R2502,R2503,R2504,R2505,R2661,R2662,R2663,R2664,R2671,R2672,R2675,R2726,R2727,R2728,R2729,R2730,R2731,R2732,R2733,R2734,R2735,R2736,R2738,R2796,R2811,R2812,R2844,R2845,R2846,R2847,R2897,R2898,R2939,R2944,R2990,R2991,R2995,R2996,R3036,R3043,R3050,R3052,R3053,R3054,R3056,R3057,R3058,R3059,R3060,R3061,R3063,R3065,R3112,R3113,R3114,R3156,R3157,R3158,R3185,R3186,R3187,R3188,R3189,R3191,R3193,R3203,R3228,R3229,R3230,R3231,R3234,R3238,R3239,R3301,R3324,R3340,R3341,R3397,R3476,R3477,R3478,R3479,R3480,R3481,R3482,R3483,R3484,R3485,R3486,R3496,R3497,R3505,R3533,R3534,R3553,R3554,R3568,R3569,R3572,R3573,R3576,R3577,R3586,R3587,R3588,R3589,R3590,R3591,R3592,R3593,R3594,R3595,R3600,R3601,R3711,R3712,R3754,R3756,R3858,R4021,R4022,R4023,R4042,R4043,R4044,R4045,R4046,R4047,R4048,R4049,R4050,R4051,R4052,R4057,R4087,R4089,R4143,R4144,R4145,R4146,R4147,R4148,R4149,R4150,R4151,R4152,R4157,R4170,R4171,R4172,R4174,R4175,R4178,R4179,R4180,R4181,R4182,R4183,R4259,R4266,R4267,R4392,R4393,R4394,R4399,R4400,R4407,R4408,R4413,R4414,R4477,R4478,R4479,R4480,R4481,R4495,R4496,R4497,R4502,R4505,R4506,R4507,R4508,R4509,R4510,R4512,R4530,R4540,R4541,R4556,R4557,R4558,R4563,R4608,R4609,R4610,R4611,R4612,R4614,R4616,R4617,R4618,R4621,R4677,R4714,R4715,R4723,R4746,R4747,R4751,R4754,R4755,R4760,R4765,R4771 |
| 274 | CS03322FB03 | RES CHIP 33.2 1/16W +-1%(0402)EF | CYNTEC CO., LTD. | WR04X33R2FTR | 1 | R3654 |
| 275 | CS03322FB03 | RES CHIP 33.2 1/16W +-1%(0402)EF | CYNTEC CO., LTD. | WR04X33R2FTR | 1 | R3909 |
| 277 | CS04992FB07 | RES CHIP 49.9 1/16W +-1%(0402)EF | CYNTEC CO., LTD. | RR0510S-49R9-FTF | 75 | PR1380,PR1390,PR1400,PR1410,R143,R195,R196,R548,R556,R558,R560,R575,R576,R698,R780,R1201,R1215,R1455,R1456,R1710,R1717,R1718,R2381,R2473,R2512,R2554,R2917,R2924,R2925,R3205,R3315,R3390,R3391,R3392,R3468,R3469,R3515,R3875,R3876,R3877,R3878,R3879,R3880,R3881,R3882,R3883,R3884,R3885,R3886,R3887,R3888,R3889,R3890,R3891,R3892,R3893,R3894,R3895,R3896,R3897,R3898,R3899,R3900,R3901,R3902,R3903,R3904,R3905,R3906,R4476,R4550,R4750,R4759,R4766,R4767 |
| 282 | CS06042FB03 | RES CHIP 60.4 1/16W +-1%(0402)EF | CYNTEC CO., LTD. | RR0510S-60R4-FTF | 1 | R477 |
| 283 | CS07502FB04 | RES CHIP 75 1/16W +-1%(0402)EF | CYNTEC CO., LTD. | RR0510S-750-FTF | 6 | R742,R744,R748,R749,R774,R1266 |
| 285 | CS11002FB07 | RES CHIP 100 1/16W +-1%(0402)EF | CYNTEC CO., LTD. | RR0510S-101-FTF | 93 | PR519,PR520,PR521,PR522,PR527,PR531,PR558,PR559,PR560,PR561,PR566,PR567,PR568,PR569,PR574,PR578,PR586,PR587,PR591,PR592,R2,R5,R6,R22,R23,R51,R52,R62,R65,R66,R135,R137,R151,R153,R155,R156,R157,R158,R175,R177,R179,R181,R183,R184,R185,R186,R200,R202,R219,R220,R243,R244,R328,R495,R555,R557,R559,R776,R1024,R1200,R1346,R1366,R1367,R1370,R1487,R1735,R1856,R1895,R1896,R1897,R1898,R2553,R2590,R2593,R3180,R3208,R3216,R3217,R4293,R4294,R4295,R4296,R4297,R4298,R4299,R4300,R4301,R4302,R4395,R4396,R4401,R4402,R4625 |
| 286 | CS11132FB02 | RES CHIP 113 1/16W +-1%(0402)EF | CYNTEC CO., LTD. | RR0510S-1130-FTF | 1 | R496 |
| 287 | CS11202FB02 | RES CHIP 120 1/16W +-1%(0402)EF | CYNTEC CO., LTD. | RR0510S-121-FTF | 1 | R757 |
| 288 | CS11302FB03 | RES CHIP 130 1/16W +-1%(0402)EF | CYNTEC CO., LTD. | RR0510S-131-FTF | 34 | R1044,R1195,R1371,R3068,R3069,R3070,R3071,R3072,R3073,R3074,R3075,R3078,R3079,R3080,R3081,R3082,R3083,R3084,R3085,R3086,R3087,R3088,R3089,R3090,R3091,R3092,R3093,R3094,R3095,R3096,R3097,R3098,R3099,R3100 |
| 289 | CS11502FB07 | RES CHIP 150 1/16W +-1%(0402)EF | CYNTEC CO., LTD. | RR0510S-151-FTF | 18 | R310,R741,R743,R747,R750,R751,R758,R759,R779,R2368,R2399,R2559,R2578,R2596,R4388,R4389,R4390,R4391 |
| 290 | CS12002FB06 | RES CHIP 200 1/16W +-1%(0402)EF | CYNTEC CO., LTD. | RR0510S-201-FTF | 7 | R4,R14,R17,R57,R60,R64,R497 |
| 291 | CS12402FB01 | RES CHIP 240 1/16W +-1%(0402)EF | CYNTEC CO., LTD. | RR0510S-241-FTF | 19 | R252,R253,R254,R258,R259,R260,R265,R275,R277,R282,R290,R910,R911,R963,R964,R969,R970,R971,R972 |
| 292 | CS12436F201 | RES CHIP 243 1/4W +-1%(1206)EF | RALEC ELECTRONIC CO. | FTT062430FTP | 4 | R4638,R4639,R4640,R4641 |
| 293 | CS12492FB02 | RES CHIP 249 1/16W +-1%(0402)EF | CYNTEC CO., LTD. | RR0510S-2490-FTF | 4 | R366,R1241,R1243,R4711 |
| 294 | CS13012FB02 | RES CHIP 301 1/16W +-1%(0402)EF | CYNTEC CO., LTD. | RR0510S-3010-FTF | 8 | R197,R198,R296,R298,R301,R303,R1242,R1244 |
| 295 | CS14702FB04 | RES CHIP 470 1/16W +-1%(0402)EF | KOASPEER ELECTRONICS INC. | RK73H1EVTTP4700F | 3 | PR1653,R3101,R3102 |
| 296 | CS14992FB06 | RES CHIP 499 1/16W +-1%(0402)EF | CYNTEC CO., LTD. | RR0510S-4990-FTF | 24 | PR4219,PR4226,PR4229,PR4237,PR4240,PR4241,PR4247,PR4250,PR4258,PR4265,R18,R19,R49,R50,R662,R663,R664,R669,R679,R680,R681,R686,R760,R761 |
| 297 | CS15602FB03 | RES CHIP 560 1/16W +-1%(0402)EF | YAGEO CORPORATION | WR04X5600FTR | 10 | R977,R978,R979,R980,R4702,R4703,R4704,R4705,R4706,R4707 |
| 298 | CS16802FB03 | RES CHIP 680 1/16W +-1%(0402)EF | CYNTEC CO., LTD. | RR0510S-681-FTF | 1 | R3653 |
| 299 | CS16812FB02 | RES CHIP 681 1/16W +-1%(0402)EF | YAGEO CORPORATION | RC0402FR-07681RP | 1 | PR106 |
| 301 | CS21002FB06 | RES CHIP 1K 1/16W +-1%(0402)EF | CYNTEC CO., LTD. | RR0510S-102-FTF | 179 | PR215,PR217,PR370,PR372,R223,R307,R361,R369,R379,R420,R423,R487,R494,R537,R539,R587,R611,R615,R622,R629,R650,R661,R678,R710,R714,R718,R767,R768,R771,R772,R773,R778,R819,R820,R821,R822,R839,R840,R841,R842,R965,R966,R967,R968,R1004,R1026,R1124,R1126,R1128,R1129,R1203,R1221,R1253,R1255,R1267,R1317,R1320,R1324,R1325,R1333,R1335,R1347,R1356,R1365,R1368,R1369,R1374,R1380,R1381,R1382,R1383,R1462,R1473,R1474,R1476,R1493,R1499,R1527,R1605,R1654,R1741,R1750,R1823,R1905,R1906,R1907,R1908,R2133,R2222,R2227,R2235,R2241,R2243,R2296,R2309,R2311,R2365,R2373,R2375,R2377,R2383,R2392,R2393,R2396,R2404,R2490,R2491,R2492,R2493,R2494,R2495,R2496,R2497,R2506,R2507,R2522,R2524,R2525,R2551,R2556,R2568,R2569,R2571,R2575,R2589,R2694,R2696,R2975,R2977,R2980,R3026,R3027,R3039,R3040,R3055,R3133,R3134,R3135,R3136,R3150,R3152,R3154,R3155,R3173,R3176,R3454,R3704,R3707,R3709,R3925,R4019,R4029,R4039,R4040,R4041,R4053,R4054,R4055,R4185,R4187,R4189,R4191,R4193,R4195,R4197,R4199,R4201,R4203,R4205,R4207,R4581,R4583,R4585,R4590,R4592,R4598,R4623,R4678,R4806 |
| 302 | CS21002FB06 | RES CHIP 1K 1/16W +-1%(0402)EF | CYNTEC CO., LTD. | RR0510S-102-FTF | 2 | R3278,R3284 |
| 305 | CS21212FB05 | RES CHIP 1.21K 1/16W +-1%(0402)EF | KOASPEER ELECTRONICS INC. (KOA CORPORATION) | RK73H1EVTTP1211F | 1 | R1800 |
| 307 | CS21332FB05 | RES CHIP 1.33K 1/16W +-1%(0402)EF | RALEC ELECTRONIC CO. | FTT021331FTH | 1 | PR4008 |
| 308 | CS21502FB07 | RES CHIP 1.5K 1/16W +-1%(0402)EF | CYNTEC CO., LTD. | RR0510S-152-FTF | 14 | R203,R204,R205,R206,R237,R238,R1216,R1217,R4397,R4398,R4403,R4404,R4409,R4410 |
| 309 | CS22002BB07 | RES CHIP 2K 1/16W +-0.1%(0402)EF | RALEC ELECTRONIC CO. | FTT022001BTH | 10 | PR1101,PR1131,PR1133,PR3914,PR3915,PR3918,PR3986,PR3987,PR3990,PR3991 |
| 310 | CS22002FB07 | RES CHIP 2K 1/16W +-1%(0402)EF | CYNTEC CO., LTD. | RR0510S-202-FTF | 39 | PR1649,R106,R990,R991,R1402,R1403,R1404,R1405,R1406,R1407,R1408,R1409,R1410,R1411,R1412,R1413,R1414,R1417,R1418,R1419,R1420,R1421,R1445,R1451,R1452,R1453,R1454,R1545,R1546,R1581,R1582,R2332,R2374,R2385,R3222,R3223,R3224,R3225,R4622 |
| 311 | CS22002FB07 | RES CHIP 2K 1/16W +-1%(0402)EF | CYNTEC CO., LTD. | RR0510S-202-FTF | 1 | R2900 |
| 312 | CS22202JB07 | RES CHIP 2.2K 1/16W +-5%(0402)EF | CYNTEC CO., LTD. | RR0510S-222-JTF | 20 | R651,R652,R1089,R1090,R3395,R3396,R3535,R3536,R3582,R3583,R3723,R3724,R3725,R3726,R3727,R3728,R3729,R3730,R3731,R3732 |
| 313 | CS22492FB05 | RES CHIP 2.49K 1/16W +-1%(0402)EF | CYNTEC CO., LTD. | RR0510S-2491-FTF | 1 | PR3969 |
| 314 | CS22492FB05 | RES CHIP 2.49K 1/16W +-1%(0402)EF | CYNTEC CO., LTD. | RR0510S-2491-FTF | 1 | R1675 |
| 317 | CS23572FB05 | RES CHIP 3.57K 1/16W +-1%(0402)EF | YAGEO CORPORATION | RC0402FR-073K57P | 1 | PR358 |
| 319 | CS24322FB03 | RES CHIP 4.32K 1/16W +-1%(0402)EF | CYNTEC CO., LTD. | RR0510S-4321-FTF | 4 | R4016,R4036,R4037,R4038 |
| 320 | CS24532FB03 | RES CHIP 4.53K 1/16W +-1%(0402)EF | CYNTEC CO., LTD. | RR0510S-4531-FTF | 2 | PR3824,PR5481 |
| 321 | CS24702FB06 | RES CHIP 4.7K 1/16W +-1%(0402)EF | CYNTEC CO., LTD. | RR0510S-472-FTF | 32 | R410,R415,R478,R568,R570,R574,R930,R1593,R1785,R2488,R2843,R3162,R3167,R3184,R3190,R3295,R3296,R3322,R3608,R3611,R3616,R3622,R3623,R3624,R3627,R3763,R4090,R4091,R4092,R4093,R4094,R4568 |
| 322 | CS24702FB06 | RES CHIP 4.7K 1/16W +-1%(0402)EF | CYNTEC CO., LTD. | RR0510S-472-FTF | 2 | R2587,R3936 |
| 323 | CS24702FB06 | RES CHIP 4.7K 1/16W +-1%(0402)EF | CYNTEC CO., LTD. | RR0510S-472-FTF | 2 | R3266,R3292 |
| 325 | CS24702JB10 | RES CHIP 4.7K 1/16W +-5%(0402)EF | CYNTEC CO., LTD. | WR04X472 JTR | 101 | R1000,R1001,R1002,R1003,R1006,R1007,R1702,R1703,R2121,R2125,R2344,R2346,R2530,R2834,R2835,R2836,R2841,R2842,R2909,R2915,R2918,R2919,R2920,R2926,R2932,R2933,R2934,R2935,R2937,R3029,R3030,R3034,R3035,R3320,R3321,R3432,R3433,R3434,R3435,R3436,R3437,R3438,R3439,R3459,R3474,R3475,R3488,R3490,R3500,R3501,R3503,R3504,R3519,R3520,R3530,R3532,R4066,R4069,R4073,R4125,R4126,R4127,R4128,R4129,R4130,R4137,R4138,R4139,R4140,R4141,R4142,R4155,R4156,R4164,R4165,R4166,R4167,R4168,R4169,R4264,R4498,R4499,R4543,R4545,R4553,R4554,R4560,R4561,R4604,R4605,R4620,R4701,R4710,R4725,R4726,R4732,R4733,R4739,R4740,R4800,R4801 |
| 326 | CS24752FB03 | RES CHIP 4.75K 1/16W +-1%(0402)EF | CYNTEC CO., LTD. | WR04X4751FTR | 16 | R241,R242,R696,R734,R953,R1196,R1269,R1471,R1500,R1502,R2253,R4405,R4406,R4411,R4412,R4489 |
| 327 | CS24992BB04 | RES CHIP 4.99K 1/16W +-0.1%(0402)EF | RALEC ELECTRONIC CO. | FTT024991BTH | 2 | PR3927,PR3932 |
| 328 | CS25112FB04 | RES CHIP 5.11K 1/16W +-1%(0402)EF | CYNTEC CO., LTD. | RR0510S-5111-FTF | 4 | R2907,R2908,R3038,R4567 |
| 329 | CS25232FB08 | RES CHIP 5.23K 1/16W +-1%(0402)EF | YAGEO CORPORATION | WR04X5231FTR | 1 | PR318 |
| 330 | CS25362FB02 | RES CHIP 5.36K 1/16W +-1%(0402)EF | CYNTEC CO., LTD. | RR0510S-5361-FTF | 2 | PR3780,PR3822 |
| 331 | CS26192FB03 | RES CHIP 6.19K 1/16W +-1%(0402)EF | CYNTEC CO., LTD. | RR0510S-6191-FTF | 1 | R1117 |
| 332 | CS26192FB03 | RES CHIP 6.19K 1/16W +-1%(0402)EF | CYNTEC CO., LTD. | RR0510S-6191-FTF | 1 | R1689 |
| 335 | CS26802FB02 | RES CHIP 6.8K 1/16W +-1%(0402)EF | CYNTEC CO., LTD. | RR0510S-682-FTF | 1 | PR4001 |
| 336 | CS27152FB03 | RES CHIP 7.15K 1/16W +-1%(0402)EF | CYNTEC CO., LTD. | RR0510S-7151-FTF | 2 | PR3790,PR3829 |
| 337 | CS27152FB03 | RES CHIP 7.15K 1/16W +-1%(0402)EF | CYNTEC CO., LTD. | RR0510S-7151-FTF | 1 | PR3964 |
| 338 | CS27322BB09 | RES CHIP 7.32K 1/16W +-0.1% (0402)EF | WALSIN TECHNOLOGY CORPORATION | RB04BTP7321 | 1 | PR1328 |
| 339 | CS27872FB02 | RES CHIP 7.87K 1/16W +-1%(0402)EF | CYNTEC CO., LTD. | RR0510S-7871-FTF | 1 | R1799 |
| 340 | CS28252BB01 | RES CHIP 8.25K 1/16W +-0.1%(0402)EF | RALEC ELECTRONIC CO. | FTT028251BTH | 2 | PR501,PR502 |
| 341 | CS28452FB06 | RES CHIP 8.45K 1/16W +-1%( 0402)EF | CYNTEC CO., LTD. | RR0510S-8451-FTF | 2 | PR259,PR1327 |
| 342 | CS29092FB05 | RES CHIP 9.09K 1/16W +-1%(0402)EF | CYNTEC CO., LTD. | RR0510S-9091-FTF | 1 | R1791 |
| 344 | CS29762FB05 | RES CHIP 9.76K 1/16W +-1%(0402)EF | CYNTEC CO., LTD. | RR0510S-9761-FTF | 2 | PR1336,PR1339 |
| 345 | CS29762FB05 | RES CHIP 9.76K 1/16W +-1%(0402)EF | CYNTEC CO., LTD. | RR0510S-9761-FTF | 1 | PR3971 |
| 346 | CS31002BB06 | RES CHIP 10K 1/16W +-0.1%(0402)EF | KOASPEER ELECTRONICS INC. | RN731ETQTP1002B25 | 1 | PR187 |
| 347 | CS31002FB08 | RES CHIP 10K 1/16W +-1%(0402)EF | CYNTEC CO., LTD. | WR04X1002FTR | 2 | PR2106,PR3935 |
| 351 | CS31002FB08 | RES CHIP 10K 1/16W +-1%(0402)EF | CYNTEC CO., LTD. | WR04X1002FTR | 254 | PR73,R8,R26,R34,R42,R69,R70,R71,R79,R111,R147,R270,R271,R272,R273,R274,R283,R284,R285,R286,R287,R318,R319,R320,R321,R325,R326,R327,R332,R334,R372,R375,R381,R421,R422,R453,R456,R498,R515,R608,R610,R613,R618,R619,R624,R626,R628,R635,R721,R727,R735,R739,R740,R769,R770,R913,R919,R927,R928,R929,R932,R933,R934,R935,R936,R937,R938,R939,R940,R941,R942,R943,R944,R945,R946,R947,R1099,R1106,R1138,R1149,R1150,R1198,R1226,R1227,R1254,R1257,R1259,R1299,R1311,R1338,R1339,R1341,R1342,R1343,R1375,R1396,R1399,R1401,R1434,R1435,R1437,R1449,R1450,R1457,R1458,R1459,R1478,R1492,R1495,R1496,R1554,R1583,R1592,R1601,R1642,R1655,R1659,R1673,R1681,R1690,R1694,R1820,R1822,R1824,R1828,R1841,R1854,R1857,R1929,R1930,R1955,R1958,R1961,R2134,R2230,R2232,R2233,R2244,R2282,R2287,R2304,R2312,R2315,R2317,R2342,R2356,R2357,R2359,R2407,R2409,R2486,R2583,R2584,R2666,R2667,R2669,R2972,R2984,R2985,R3041,R3127,R3130,R3131,R3145,R3147,R3164,R3165,R3174,R3175,R3182,R3183,R3249,R3297,R3298,R3325,R3455,R3457,R3465,R3466,R3467,R3471,R3487,R3507,R3509,R3529,R3638,R3639,R3640,R3641,R3642,R3643,R3771,R3938,R4079,R4080,R4081,R4086,R4095,R4096,R4097,R4098,R4099,R4100,R4101,R4102,R4103,R4104,R4105,R4106,R4107,R4108,R4109,R4110,R4111,R4112,R4113,R4114,R4115,R4116,R4117,R4121,R4135,R4153,R4176,R4491,R4492,R4494,R4516,R4517,R4518,R4519,R4520,R4521,R4564,R4565,R4579,R4586,R4603,R4635,R4674,R4679,R4719,R4722,R4727,R4730,R4737,R4745,R4756,R4761,R4762,R4763,R4764,R4768,R4798 |
| 352 | CS31002FB08 | RES CHIP 10K 1/16W +-1%(0402)EF | CYNTEC CO., LTD. | WR04X1002FTR | 2 | R3660,R3663 |
| 354 | CS31002FB08 | RES CHIP 10K 1/16W +-1%(0402)EF | CYNTEC CO., LTD. | WR04X1002FTR | 2 | R4067,R4070 |
| 355 | CS31002FB08 | RES CHIP 10K 1/16W +-1%(0402)EF | CYNTEC CO., LTD. | WR04X1002FTR | 1 | R4071 |
| 356 | CS31002FB08 | RES CHIP 10K 1/16W +-1%(0402)EF | CYNTEC CO., LTD. | WR04X1002FTR | 1 | R4072 |
| 359 | CS31132BB02 | RES CHIP 11.3K 1/16W +-0.1%(0402)EF | EVER OHMS TECHNOLOGY CO., LTD. | CRG0402B11K3Q10Z | 2 | PR1310,PR1314 |
| 360 | CS31182BB06 | RES CHIP 11.8K 1/16W +-0.1%(0402)EF | WALSIN TECHNOLOGY CORPORATION | RB04BTP1182 | 1 | PR91 |
| 361 | CS31242BB10 | RES CHIP 12.4K 1/16W +-0.1%( 0402)EF | RALEC ELECTRONIC CO. | WF04H1242BTR | 2 | PR50,PR51 |
| 363 | CS31502BB03 | RES CHIP 15K  1/16W +-0.1%(0402)EF | KOASPEER ELECTRONICS INC. | RN731ETQTP1502B25 | 1 | PR830 |
| 365 | CS31502FB05 | RES CHIP 15K 1/16W +-1%(0402)EF | CYNTEC CO., LTD. | RR0510S-153-FTF | 2 | PR3791,PR3812 |
| 367 | CS31502FB05 | RES CHIP 15K 1/16W +-1%(0402)EF | CYNTEC CO., LTD. | RR0510S-153-FTF | 1 | PR3965 |
| 368 | CS31502FB05 | RES CHIP 15K 1/16W +-1%(0402)EF | CYNTEC CO., LTD. | RR0510S-153-FTF | 1 | PR4002 |
| 369 | CS31542FB02 | RES CHIP 15.4K 1/16W +-1%(0402)EF | CYNTEC CO., LTD. | RR0510S-1542-FTF | 4 | R27,R35,R43,R78 |
| 370 | CS31692FB03 | RES CHIP 16.9K 1/16W +-1%(0402)EF | CYNTEC CO., LTD. | RR0510S-1692-FTF | 1 | PR89 |
| 371 | CS31692FB03 | RES CHIP 16.9K 1/16W +-1%(0402)EF | CYNTEC CO., LTD. | RR0510S-1692-FTF | 1 | R3933 |
| 373 | CS31782FB04 | RES CHIP 17.8K 1/16W +- 1% (0402)EF | RALEC ELECTRONIC CO. | FTT021782FTH | 1 | PR4004 |
| 374 | CS31802FB04 | RES CHIP 18K 1/16W +-1%(0402)EF | WALSIN TECHNOLOGY CORPORATION | WR04X1802FTR | 1 | R3005 |
| 377 | CS32002FB06 | RES CHIP 20K 1/16W +-1%(0402)EF | CYNTEC CO., LTD. | RR0510S-203-FTF | 4 | R502,R1202,R1340,R1809 |
| 378 | CS32152FB04 | RES CHIP 21.5K 1/16W +-1%(0402)EF | CYNTEC CO., LTD. | RR0510S-2152-FTF | 1 | PR834 |
| 379 | CS32262FB02 | RES CHIP 22.6K 1/16W +-1%(0402)EF | CYNTEC CO., LTD. | RR0510S-2262-FTF | 1 | PR1303 |
| 380 | CS32322FB03 | RES CHIP 23.2K 1/16W +-1%(0402)EF | CYNTEC CO., LTD. | RR0510S-2322-FTF | 4 | R28,R36,R44,R77 |
| 381 | CS32432FB03 | RES CHIP 24.3K 1/16W +-1%(0402)EF | YAGEO CORPORATION | RC0402FR-0724K3P | 1 | PR203 |
| 383 | CS32552FB06 | RES CHIP 25.5K 1/16W +-1%(0402)EF | CYNTEC CO., LTD. | RR0510S-2552-FTF | 2 | PR3789,PR3795 |
| 384 | CS32552FB06 | RES CHIP 25.5K 1/16W +-1%(0402)EF | CYNTEC CO., LTD. | RR0510S-2552-FTF | 1 | PR3963 |
| 385 | CS32672FB03 | RES CHIP 26.7K 1/16W +-1%(0402)EF | CYNTEC CO., LTD. | RR0510S-2672-FTF | 2 | R2219,R2221 |
| 386 | CS33012FB03 | RES CHIP 30.1K 1/16W +-1%(0402)EF | KOASPEER ELECTRONICS INC. | RK73H1EVTTP3012F | 2 | PR3335,PR3336 |
| 389 | CS33162FB02 | RES CHIP 31.6K 1/16W +-1%(0402)EF | CYNTEC CO., LTD. | RR0510S-3162-FTF | 1 | R2585 |
| 390 | CS33302FB00 | RES CHIP 33K 1/16W +-1%(0402)EF | KOASPEER ELECTRONICS INC. | RK73H1EVTTP3302F | 1 | R3907 |
| 391 | CS33482FB04 | RES CHIP 34.8K 1/16W +-1%(0402)EF | YAGEO CORPORATION | RC0402FR-0734K8P | 1 | PR2222 |
| 392 | CS33572FB01 | RES CHIP 35.7K 1/16W +-1%(0402) EF | CYNTEC CO., LTD. | RR0510S-3572-FTF | 4 | R29,R37,R45,R76 |
| 393 | CS33832BB06 | RES CHIP 38.3K 1/16W +-0.1%(0402)EF | WALSIN TECHNOLOGY CORPORATION | WF04H3832BTR | 2 | PR1337,PR1340 |
| 395 | CS34702BB05 | RES CHIP 47K 1/16W +-0.1%(0402)EF | RALEC ELECTRONIC CO. | WF04H4702BTR | 1 | PR831 |
| 396 | CS35492FB03 | RES CHIP 54.9K 1/16W  +-1%(0402)EF | CYNTEC CO., LTD. | RR0510S-5492-FTF | 20 | R30,R38,R46,R75,R3461,R3463,R3464,R3492,R3494,R3498,R3508,R3510,R3511,R3513,R3514,R3521,R3522,R3523,R3524,R3525 |
| 398 | CS36042FB04 | RES CHIP 60.4K 1/16W +-1%(0402)EF | CYNTEC CO., LTD. | RR0510S-6042-FTF | 2 | PR1301,PR2220 |
| 399 | CS36342FB04 | RES CHIP 63.4K 1/16W +-1%(0402)EF | CYNTEC CO., LTD. | RR0510S-6342-FTF | 1 | R3923 |
| 400 | CS36802FB04 | RES CHIP 68K 1/16W +-1%(0402)EF | WALSIN TECHNOLOGY CORPORATION | WR04X6802FTR | 2 | R4276,R4282 |
| 403 | CS37502BB01 | RES CHIP 75K 1/16W +-0.1%(0402)EF | RALEC ELECTRONIC CO. | FTT027502BTH | 2 | PR3926,PR3931 |
| 404 | CS38202FB01 | RES CHIP 82K  1/16W +-1% (0402)EF | CYNTEC CO., LTD. | RR0510S-823-FTF | 1 | R4901 |
| 405 | CS38452FB05 | RES CHIP 84.5K 1/16W +-1%(0402)EF | CYNTEC CO., LTD. | RR0510S-8452-FTF | 4 | R31,R39,R47,R74 |
| 406 | CS38662FB05 | RES CHIP 86.6K 1/16W +-1%(0402)EF | CYNTEC CO., LTD. | RR0510S-8662-FTF | 1 | PR92 |
| 407 | CS41002FB09 | RES CHIP 100K 1/16W +-1%(0402)EF | CYNTEC CO., LTD. | WR04X1003FTR | 38 | R413,R1289,R1350,R1351,R1352,R1353,R1354,R1355,R1541,R1571,R1641,R1643,R1688,R1692,R2457,R2528,R2828,R2830,R2832,R2838,R2927,R2941,R3132,R3207,R3232,R3235,R3449,R3452,R4515,R4548,R4552,R4559,R4680,R4681,R4682,R4712,R4713,R4769 |
| 408 | CS41002FB09 | RES CHIP 100K 1/16W +-1%(0402)EF | CYNTEC CO., LTD. | WR04X1003FTR | 1 | R3665 |
| 409 | CS41002FB09 | RES CHIP 100K 1/16W +-1%(0402)EF | CYNTEC CO., LTD. | WR04X1003FTR | 4 | R3783,R3796,R3826,R3833 |
| 412 | CS41002FB09 | RES CHIP 100K 1/16W +-1%(0402)EF | CYNTEC CO., LTD. | WR04X1003FTR | 2 | R3977,R3979 |
| 413 | CS41002FB09 | RES CHIP 100K 1/16W +-1%(0402)EF | CYNTEC CO., LTD. | WR04X1003FTR | 2 | R4013,R4015 |
| 414 | CS41202FB05 | RES CHIP 120K 1/16W +-1%(0402)EF | CYNTEC CO., LTD. | RR0510S-124-FTF | 5 | PR1134,PR3912,PR3937,PR3982,PR3984 |
| 418 | CS41272FB07 | RES CHIP 127K 1/16W +-1%(0402)EF | CYNTEC CO., LTD. | RR0510S-1273-FTF | 4 | R32,R40,R48,R73 |
| 419 | CS41502FB04 | RES CHIP 150K 1/16W +-1%(0402)EF | CYNTEC CO., LTD. | RR0510S-154-FTF | 1 | PR1330 |
| 422 | CS41602FB05 | RES CHIP 160K 1/16W+-1%(0402)EF | CYNTEC CO., LTD. | RR0510S-164-FTF | 1 | PR4000 |
| 423 | CS41962FB03 | RES CHIP 196K 1/16W +-1%(0402)EF | KOASPEER ELECTRONICS INC. | RK73H1EVTTP1963F | 4 | R33,R41,R72,R80 |
| 424 | CS42002FB05 | RES CHIP 200K 1/16W +-1%(0402)EF | CYNTEC CO., LTD. | RR0510S-204-FTF | 4 | R1700,R4211,R4636,R4637 |
| 425 | CS51002FB05 | RES CHIP 1M 1/16W +-1%(0402)EF | CYNTEC CO., LTD. | RR0510S-105-FTF | 3 | R2966,R4778,R4779 |
| 427 | CS61002FB02 | RES CHIP 10M 1/16W +-1%(0402)EF | TA-I TECHNOLOGY CO.,LTD. | RM04FTW1005 | 2 | PR4523,PR4525 |
| 428 | CS61002FB02 | RES CHIP 10M 1/16W +-1%(0402)EF | TA-I TECHNOLOGY CO.,LTD. | RM04FTW1005 | 1 | PR4526 |
| 429 | CS61002FB02 | RES CHIP 10M 1/16W +-1%(0402)EF | TA-I TECHNOLOGY CO.,LTD. | RM04FTW1005 | 1 | PR4527 |
| 431 | CS61003F901 | RES CHIP 10M 1/10W +-1%(0603)EF | DALE ELECTRONICS,INC. | RCG060310M0FKEA | 1 | R120 |
| 432 | CV+10G0MZ04 | IND SMD 100NH 20% 16A(HCBS4545-101) | DELTA ELECTRONIC IND. CO., LTD. DELTA ELECTRONICS COMPONENT(WUJIANG)LTD | HCBS4545-101 | 8 | PL6,PL14,PL23,PL43,PL44,PL45,PL101,PL110 |
| 433 | CV+12^0EZ03 | IND SMD 120NH 15% 69A(PGL6312.121AHLT) | PULSE | PGL6312.121AHLT | 8 | PL4,PL5,PL17,PL21,PL22,PL35,PL105,PL106 |
| 434 | CV+13^0KZ11 | IND SMD 130NH 10% 106A(PG2323.131HLT) | PULSE | PG2323.131HLT | 8 | PL2,PL12,PL18,PL19,PL33,PL34,PL113,PL210 |
| 435 | CV+15^0TZ04 | IND SMD 150NH 15% 82A(PGL6303.151HLT) | PULSE | PGL6303.151HLT | 16 | PL7,PL8,PL9,PL10,PL11,PL13,PL24,PL25,PL26,PL27,PL28,PL29,PL30,PL31,PL112,PL114 |
| 436 | CV+30Y0KZ05 | IND SMD 300NH 10% 33A(PG1712.301AHLT) | PULSE | PG1712.301AHLT | 3 | PL3,PL20,PL150 |
| 437 | CV+68F5MZ05 | IND SMD 0.68U +-20%,15.5A PCMC063T-R68MN | CYNTEC CO., LTD. | PCMC063T-R68MN | 2 | PL118,PL119 |
| 438 | CV-15^0MZ02 | IND SMD 1.5UH 20% 53A(EM-15AM17VG1-QS) | TRIO TECHNOLGY CO., LTD. | EM-15AM17VG1-QS | 1 | PL66 |
| 439 | CV-2280MZ15 | IND SMD 2.2UH +-20% 8A(PCMC063T-2R2MN) | CYNTEC CO., LTD. | PCMC063T-2R2MN | 1 | PL170 |
| 440 | CV-4755MZ12 | IND SMD 4.7U20%5.5A(PCMC063T-4R7MN) | CYNTEC CO., LTD. | PCMC063T-4R7MN | 2 | PL120,PL121 |
| 441 | CV-47A0MZ10 | IND SMD 4.7UH +-20% 10A(PCMB104E-4R7MS) | CYNTEC CO., LTD. | PCMB104E-4R7MS | 1 | PL65 |
| 442 | CVA50^0EZ01 | IND SMD 50NH 15% 148A(PGL6189.500HLT) | PULSE | PGL6189.500HLT | 2 | PL15,PL32 |
| 443 | CX220TN1001 | EMI FILTER BLM18SN220TN1D(22,8000MA) | MURATA ERIE N.A. INC TAIWAN BRANCH Okayama Murata Mfg.Co.,Ltd.Wakura Murata Mfg. Co., Ltd. (Peregrine Semiconductor Corp) | BLM18SN220TN1D | 2 | PL16,PL64 |
| 444 | CX5PX121001 | EMI FILTER BLM15PX121SN1D(120,2A) | MURATA ERIE N.A. INC TAIWAN BRANCH Okayama Murata Mfg.Co.,Ltd.Wakura Murata Mfg. Co., Ltd. (Peregrine Semiconductor Corp) | BLM15PX121SN1D | 1 | L18 |
| 445 | CX601T05003 | EMI FILTER FCM2012KF-601T05(600,0.5A) | TAI-TECH ADVANCED ELECTRONICS CO. | FCM2012KF-601T05 | 6 | L1,L13,L14,L17,L19,L20 |
| 446 | CX8PG300001 | EMI FILTER SBK160808T-100Y-N(10,500MA) | MURATA ERIE N.A. INC TAIWAN BRANCH Okayama Murata Mfg.Co.,Ltd.Wakura Murata Mfg. Co., Ltd. (Peregrine Semiconductor Corp) | BLM18PG300SN1D | 1 | L15 |
| 448 | CX8SG331000 | EMI FILTER BLM18SG331TN1D(330,1.5A) | MURATA ERIE N.A. INC TAIWAN BRANCH Okayama Murata Mfg.Co.,Ltd.Wakura Murata Mfg. Co., Ltd. (Peregrine Semiconductor Corp) | BLM18SG331TN1E | 2 | L3,L4 |
| 449 | DFHD03MS213 | CONN DIP HEADER 3P 1R MS(P2.54,H8.6) | PINREX TECHNOLOGY CORP | 210-HP1-030BR1 | 6 | JP7,JP10,JP15,JP16,JP4003,PJP1 |
| 450 | DFHD08MS392 | CONN DIP HEADER 8P 1R MS(P2.54,H8.6) | PINREX TECHNOLOGY CORP | 210-HP1-080BR1 | 1 | J43 |
| 451 | DFHD14MS170 | CONN DIP HEADER 14P 2R MS(P2.54,H8.6) | PINREX TECHNOLOGY CORP | 210-HP2-07GBR1 | 1 | J104 |
| 452 | DFHD20MS193 | CONN SMD HEADER 20P 2R MS(P2,H6.4) | ACES ELECTRONIC CO., LTD. | 51386-0200C-V01 | 1 | J100 |
| 453 | DFHD60MR024 | CONN DIP HEADER 60P 4R MR(P2.54,H12.57) | AMPHENOL EAST ASIA LIMITED (Amphenol-TCS) (Shanghai Amphenol Airwave Communication Electronics Co.,Ltd) | 10106263-6003K02LF | 1 | J45 |
| 454 | DFHS02FR062 | CONN DIP HOUSING 2P 1R FR(P20,H8.80) | LOTES(CHIA TSE TERMINAL INDUSTRYLOTES SUZHOU CO.,LTD | AAA-BAT-029-Y19 | 1 | BT1 |
| 455 | DFHS03FR030 | CONN DIP HOUSING 3P 1R FR(H14.7) | AMPHENOL EAST ASIA LIMITED (Amphenol-TCS) (Shanghai Amphenol Airwave Communication Electronics Co.,L......(Skip) | 10165288-101LF | 2 | J122,J123 |
| 457 | DFHS56FS022 | CONN SMD HOUSING 56P 2R FS(P0.6, H9.25) | TYCO ELECTRONICS TAIWAN CO.,LTD. (Raychem)COEY MAGNETICS(Sensormatic Hong Kong Limited) TE Connectivity | 1-2327679-3 | 1 | J90 |
| 458 | DFHS60FS108 | CONN SMD HOUSING 60P 2R FS(P0.5,H3.05) | SAMTEC INC. | ASP-214108-01 | 1 | J42 |
| 459 | DFHS75FR313 | CONN SMD HOUSING 75P 2R FR(P0.5,H6.7) | LOTES(CHIA TSE TERMINAL INDUSTRYLOTES SUZHOU CO.,LTD | APCI0155-P004A | 1 | J59 |
| 460 | DFHSB2FR012 | CONN DIP HOUSING 112P 8R FR(P1.2,H17.9) | BERG ELECTRONICS (FCI) | 10137002-101LF | 7 | J105,J106,J107,J108,J109,J110,J111 |
| 461 | DFHSG0FR007 | CONN DIP HOUSING 160P 8R FR(P1.2,H25.1) | BERG ELECTRONICS (FCI) | 10131762-101LF | 1 | J112 |
| 462 | DFHSG8FR011 | CONN SMD HOUSING 168P 2R FR(P0.6,H5.35) | AMPHENOL EAST ASIA LIMITED (Amphenol-TCS) (Shanghai Amphenol Airwave Communication Electronics Co.,Ltd) | ME1016810202011 | 3 | J35,J37,J41 |
| 463 | DFHST8FS460 | CONN SMD HS DDR5 288P 2R FS(P0.85,H21.3) | LOTES(CHIA TSE TERMINAL INDUSTRYLOTES SUZHOU CO.,LTD | ADR50017-P087CC | 16 | J2,J4,J6,J8,J10,J12,J14,J16,J18,J20,J22,J24,J26,J28,J30,J32 |
| 464 | DFHST8FS461 | CONN SMD HS DDR5 288P 2R FS(P0.85,H21.3) | LOTES(CHIA TSE TERMINAL INDUSTRYLOTES SUZHOU CO.,LTD | ADR50017-P130CC | 16 | J1,J3,J5,J7,J9,J11,J13,J15,J17,J19,J21,J23,J25,J27,J29,J31 |
| 465 | DGA^7000023 | SOCKET 4677P E LGA(P0.9398,H8.64) | LOTES(CHIA TSE TERMINAL INDUSTRYLOTES SUZHOU CO.,LTD | AZIF0045-P001C01CS | 2 | U1,U2 |
| 466 | DHP00061N15 | SWITCH TACT SMD DTSM-61N-S-Q-T/R | Diptronics Manufacturing Inc. | DTSM-61N-S-Q-T/R | 1 | SW5 |
| 467 | DKK00XFU000 | FUSE SMD 20A/125V(FAST,UL/CSA) | LITTELFUSE INC. | 0456020.ER | 1 | FS1 |
| 468 | DFHS56FR016 | CONN SMD HS 56P 2R FR(P0.6, H20.125) | TYCO ELECTRONICS TAIWAN CO.,LTD. (Raychem)COEY MAGNETICS(Sensormatic Hong Kong Limited) TE Connectivity | 2360871-1 | 1 | J90_CON |
| 469 | DEJP0020021 | MINI JUMPER 2.54MM(5.0*2.4*6.0) BK | ACES ELECTRONIC CO., LTD. | 57928-00211-V01 | 3 | JP15_23,JP16_23,JP4003_12 |
| 470 | DGRA^000178 | CPU SKTSUP LGA4677 E BL(LTS) | LOTES(CHIA TSE TERMINAL INDUSTRYLOTES SUZHOU CO.,LTD | AZIF0190-P005C01 | 2 | U1_BL,U2_BL |
| 471 | DGRA^000128 | CPU SKTSUP LGA4677 E BP(LTS) | LOTES(CHIA TSE TERMINAL INDUSTRYLOTES SUZHOU CO.,LTD | AHSK0044-P001C01 | 2 | U1_BP,U2_BP |
| 472 | DGRA^000180 | CPU SKTSUP LGA4677 E CV(LTS) | LOTES(CHIA TSE TERMINAL INDUSTRYLOTES SUZHOU CO.,LTD | AZIF0229-P004C01 | 2 | U1_DC,U2_DC |
| 473 | AHL03003097 | BATTERY LI,3V,220MAH(BCR2032HT) | Double Best Corporation Limited (DBV) | BCR2032HT | 1 | BT1_BAT |
| 474 | DFHS03FR030 | CONN DIP HOUSING 3P 1R FR(H14.7) | AMPHENOL EAST ASIA LIMITED (Amphenol-TCS) (Shanghai Amphenol Airwave Communication Electronics Co.,L......(Skip) | 10165288-101LF | 2 |  |
| 475 | MBF0T004010 | NUT SMT M2*2 F0T(MBF0T004,R3A)STEEL | HUANG YIH  Industrial Co., Ltd(Rayhome) | MBF0T00401 | 4 |  |
| 476 | FBF0C041010 | MB AIR BAFFLE GUIDE PIN F0C(FBF0C041,3A) | HUANG YIH  Industrial Co., Ltd(Rayhome) | FBF0C04101 | 1 |  |
| 477 | MBF0G001010 | SMT NUT M.2 LATCH F0G(MBF0G001,R3A)STEEL | ASCEND TOWER ENTERPRISE CO.,LTD (ASCEND TOP ENTERPRISE CO., LTD) | MBF0G00101 | 2 |  |
| 478 | MM20070C020 | SCREW M2*7.0-C(BNI,NYLOK,D6,T2)STEEL | SCREW TECH INDUDTRY CO., LTD. | MM20070C020 | 4 |  |
| 479 | MS30050I070 | SCREW M3.0*5.0-I(NI) (NYLOK)IRON | SCREW TECH INDUDTRY CO., LTD. | M30050I07 | 2 |  |
| 480 | FBF0T006010 | HANDLE MB TOP F0T(FBF0T006,R3A)FVT | Fivetech Technology Inc. | FBF0T00601 | 1 |  |
| 481 | MS30050I290 | SCREW M3*5-I(ZN)(NYLOK)STEEL(D8,T1.5) | SCREW TECH INDUDTRY CO., LTD. | M30050I29 | 1 |  |
| 482 | MM16045P000 | SCREW M1.6*4.5-P(NI,NYLOK,D3.2,T1.3)STL | SCREW TECH INDUDTRY CO., LTD. | SCREW M1.6*4.5-P(NI,NYLOK,D3.2,T1.3)STL | 2 |  |
| 483 | MS50060PI60 | SCREW M5.0*6.0-P(NI)(NYLOK)STEEL | SCREW TECH INDUDTRY CO., LTD. | SCREW M5*6-I(ZN)(NYLOK)STEEL | 4 |  |
| 484 | GAF09018010 | MB RECTANGL SI RUBBER F09B | SHEN CHI RUBBER CO.,LTD. | GAF0901801 | 1 |  |
| 485 | MBF0E004010 | NUT MB TPM M3 F0E(MBF0E004,REV3A)STEEL | HUANG YIH  Industrial Co., Ltd(Rayhome) | MBF0E00401 | 1 |  |
| 486 | JXF0G001010 | M.2HANDLE LATCH H6.7 F0G(JXF0G001,3A)FVT | Fivetech Technology Inc. | JXF0G00101 | 1 |  |
| 487 | FBF0T141010 | HANDLE MB F0T(FBF0T141,R3A)FVT | Fivetech Technology Inc. | FBF0T14101 | 1 |  |
| 488 | MU06060BCI2 | SCREW #6-32UNC*6-B(NYLOK)IRON | SCREW TECH INDUDTRY CO., LTD. | MU06060BCI2 | 2 |  |
| 489 | FBF0C045010 | THUMB SCREW SMT F0C(FBF0C045,REV3A)FVT | Fivetech Technology Inc. | FBF0C04501 | 21 |  |
| 490 | FBF0T005010 | PCH HS | AURAS TECHNOLOGY COMPANY (AURAS TECHNOLOGY (KUNSHAN) CO., LTD)  Pel horng(GuangZhou) Technology Co.,......(Skip) | FBF0T00501 | 1 |  |
| 491 | FBF0T004010 | VR HS | AURAS TECHNOLOGY COMPANY (AURAS TECHNOLOGY (KUNSHAN) CO., LTD)  Pel horng(GuangZhou) Technology Co.,......(Skip) | FBF0T00401 | 2 |  |
